G04 ================== begin FILE IDENTIFICATION RECORD ==================*
G04 Layout Name:  9054_F0T_PDB_BD_GPU_F_V04_1213_1550.brd*
G04 Film Name:    vcc1*
G04 File Format:  Gerber RS274X*
G04 File Origin:  Cadence Allegro 17.2-S081*
G04 Origin Date:  Wed Dec 28 10:19:02 2022*
G04 *
G04 Layer:  DRAWING FORMAT/TITLE_BLOCK_A*
G04 Layer:  PIN/SPECIAL_DRILL*
G04 Layer:  DRAWING FORMAT/TITLE_BLOCK*
G04 Layer:  VIA CLASS/VCC1*
G04 Layer:  PIN/VCC1*
G04 Layer:  MANUFACTURING/PHOTOPLOT_OUTLINE*
G04 Layer:  ETCH/VCC1*
G04 Layer:  DRAWING FORMAT/TITLE_DATA_VCC1*
G04 *
G04 Offset:    (0.00 0.00)*
G04 Mirror:    No*
G04 Mode:      Negative*
G04 Rotation:  0*
G04 FullContactRelief:  No*
G04 UndefLineWidth:     6.00*
G04 ================== end FILE IDENTIFICATION RECORD ====================*
%FSLAX25Y25*MOIN*%
%IR0*IPPOS*OFA0.00000B0.00000*MIA0B0*SFA1.00000B1.00000*%
%ADD11C,.03*%
%ADD44C,.042*%
%ADD49C,.061*%
%ADD19C,.07*%
%ADD43C,.026*%
%ADD20C,.07*%
%AMMACRO15*
4,1,36,0.0,.01,
-.001736,.009848,
-.00342,.009397,
-.005,.00866,
-.006428,.00766,
-.00766,.006428,
-.00866,.005,
-.009397,.00342,
-.009848,.001736,
-.01,0.0,
-.009848,-.001736,
-.009397,-.00342,
-.00866,-.005,
-.00766,-.006428,
-.006428,-.00766,
-.005,-.00866,
-.00342,-.009397,
-.001736,-.009848,
0.0,-.01,
.001736,-.009848,
.00342,-.009397,
.005,-.00866,
.006428,-.00766,
.00766,-.006428,
.00866,-.005,
.009397,-.00342,
.009848,-.001736,
.01,0.0,
.009848,.001736,
.009397,.00342,
.00866,.005,
.00766,.006428,
.006428,.00766,
.005,.00866,
.00342,.009397,
.001736,.009848,
0.0,.01,
0.0*
%
%ADD15MACRO15*%
%AMMACRO30*
4,1,36,.0025,0.0,
.002462,.000434,
.002349,.000855,
.002165,.00125,
.001915,.001607,
.001607,.001915,
.00125,.002165,
.000855,.002349,
.000434,.002462,
0.0,.0025,
-.000434,.002462,
-.000855,.002349,
-.00125,.002165,
-.001607,.001915,
-.001915,.001607,
-.002165,.00125,
-.002349,.000855,
-.002462,.000434,
-.0025,0.0,
-.002462,-.000434,
-.002349,-.000855,
-.002165,-.00125,
-.001915,-.001607,
-.001607,-.001915,
-.00125,-.002165,
-.000855,-.002349,
-.000434,-.002462,
0.0,-.0025,
.000434,-.002462,
.000855,-.002349,
.00125,-.002165,
.001607,-.001915,
.001915,-.001607,
.002165,-.00125,
.002349,-.000855,
.002462,-.000434,
.0025,0.0,
270.*
%
%ADD30MACRO30*%
%AMMACRO29*
4,1,36,.0025,0.0,
.002462,.000434,
.002349,.000855,
.002165,.00125,
.001915,.001607,
.001607,.001915,
.00125,.002165,
.000855,.002349,
.000434,.002462,
0.0,.0025,
-.000434,.002462,
-.000855,.002349,
-.00125,.002165,
-.001607,.001915,
-.001915,.001607,
-.002165,.00125,
-.002349,.000855,
-.002462,.000434,
-.0025,0.0,
-.002462,-.000434,
-.002349,-.000855,
-.002165,-.00125,
-.001915,-.001607,
-.001607,-.001915,
-.00125,-.002165,
-.000855,-.002349,
-.000434,-.002462,
0.0,-.0025,
.000434,-.002462,
.000855,-.002349,
.00125,-.002165,
.001607,-.001915,
.001915,-.001607,
.002165,-.00125,
.002349,-.000855,
.002462,-.000434,
.0025,0.0,
180.*
%
%ADD29MACRO29*%
%ADD38C,.066*%
%ADD35C,.06015*%
%ADD32C,.087*%
%AMMACRO18*
4,1,36,0.0,.0135,
-.002344,.013295,
-.004617,.012686,
-.00675,.011691,
-.008678,.010342,
-.010342,.008678,
-.011691,.00675,
-.012686,.004617,
-.013295,.002344,
-.0135,0.0,
-.013295,-.002344,
-.012686,-.004617,
-.011691,-.00675,
-.010342,-.008678,
-.008678,-.010342,
-.00675,-.011691,
-.004617,-.012686,
-.002344,-.013295,
0.0,-.0135,
.002344,-.013295,
.004617,-.012686,
.00675,-.011691,
.008678,-.010342,
.010342,-.008678,
.011691,-.00675,
.012686,-.004617,
.013295,-.002344,
.0135,0.0,
.013295,.002344,
.012686,.004617,
.011691,.00675,
.010342,.008678,
.008678,.010342,
.00675,.011691,
.004617,.012686,
.002344,.013295,
0.0,.0135,
0.0*
%
%ADD18MACRO18*%
%AMMACRO45*
4,1,17,.09027,.06198,
.099661,.045363,
.106024,.027368,
.109166,.008541,
.108991,-.010545,
.105504,-.029311,
.098811,-.047186,
.09027,-.06198,
.0953,-.06701,
.105488,-.049443,
.112471,-.030374,
.116037,-.010382,
.116077,.009925,
.11259,.029931,
.105682,.049027,
.095563,.066634,
.0953,.06701,
.09027,.06198,
90.*
4,1,17,.06198,-.09027,
.045363,-.099661,
.027368,-.106024,
.008541,-.109166,
-.010545,-.108991,
-.029311,-.105504,
-.047186,-.098811,
-.06198,-.09027,
-.06701,-.0953,
-.049443,-.105488,
-.030374,-.112471,
-.010382,-.116037,
.009925,-.116077,
.029931,-.11259,
.049027,-.105682,
.066634,-.095563,
.06701,-.0953,
.06198,-.09027,
90.*
4,1,17,-.09027,-.06198,
-.099661,-.045363,
-.106024,-.027368,
-.109166,-.008541,
-.108991,.010545,
-.105504,.029311,
-.098811,.047186,
-.09027,.06198,
-.0953,.06701,
-.105488,.049443,
-.112471,.030374,
-.116037,.010382,
-.116077,-.009925,
-.11259,-.029931,
-.105682,-.049027,
-.095563,-.066634,
-.0953,-.06701,
-.09027,-.06198,
90.*
4,1,17,-.06198,.09027,
-.045363,.099661,
-.027368,.106024,
-.008541,.109166,
.010545,.108991,
.029311,.105504,
.047186,.098811,
.06198,.09027,
.06701,.0953,
.049443,.105488,
.030374,.112471,
.010382,.116037,
-.009925,.116077,
-.029931,.11259,
-.049027,.105682,
-.066634,.095563,
-.06701,.0953,
-.06198,.09027,
90.*
%
%ADD45MACRO45*%
%ADD21C,.04952*%
%AMMACRO47*
4,1,15,.02475,.01414,
.026829,.009627,
.028094,.004822,
.028504,-.000129,
.028049,-.005077,
.026741,-.009871,
.02475,-.01414,
.02984,-.01923,
.032726,-.013756,
.034617,-.007864,
.035457,-.001734,
.03522,.00445,
.033912,.010498,
.031574,.016227,
.02984,.01923,
.02475,.01414,
90.*
4,1,15,.01414,-.02475,
.009627,-.026829,
.004822,-.028094,
-.000129,-.028504,
-.005077,-.028049,
-.009871,-.026741,
-.01414,-.02475,
-.01923,-.02984,
-.013756,-.032726,
-.007864,-.034617,
-.001734,-.035457,
.00445,-.03522,
.010498,-.033912,
.016227,-.031574,
.01923,-.02984,
.01414,-.02475,
90.*
4,1,15,-.02475,-.01414,
-.026829,-.009627,
-.028094,-.004822,
-.028504,.000129,
-.028049,.005077,
-.026741,.009871,
-.02475,.01414,
-.02984,.01923,
-.032726,.013756,
-.034617,.007864,
-.035457,.001734,
-.03522,-.00445,
-.033912,-.010498,
-.031574,-.016227,
-.02984,-.01923,
-.02475,-.01414,
90.*
4,1,15,-.01414,.02475,
-.009627,.026829,
-.004822,.028094,
.000129,.028504,
.005077,.028049,
.009871,.026741,
.01414,.02475,
.01923,.02984,
.013756,.032726,
.007864,.034617,
.001734,.035457,
-.00445,.03522,
-.010498,.033912,
-.016227,.031574,
-.01923,.02984,
-.01414,.02475,
90.*
%
%ADD47MACRO47*%
%AMMACRO39*
4,1,16,.02657,.01597,
.02894,.011114,
.03043,.005919,
.030995,.000545,
.030619,-.004845,
.029313,-.010088,
.027115,-.015025,
.02657,-.01597,
.03164,-.02104,
.034813,-.015226,
.036928,-.00895,
.037921,-.002401,
.037762,.00422,
.036455,.010713,
.034041,.016881,
.03164,.02104,
.02657,.01597,
90.*
4,1,16,.01597,-.02657,
.011114,-.02894,
.005919,-.03043,
.000545,-.030995,
-.004845,-.030619,
-.010088,-.029313,
-.015025,-.027115,
-.01597,-.02657,
-.02104,-.03164,
-.015226,-.034813,
-.00895,-.036928,
-.002401,-.037921,
.00422,-.037762,
.010713,-.036455,
.016881,-.034041,
.02104,-.03164,
.01597,-.02657,
90.*
4,1,16,-.02657,-.01597,
-.02894,-.011114,
-.03043,-.005919,
-.030995,-.000545,
-.030619,.004845,
-.029313,.010088,
-.027115,.015025,
-.02657,.01597,
-.03164,.02104,
-.034813,.015226,
-.036928,.00895,
-.037921,.002401,
-.037762,-.00422,
-.036455,-.010713,
-.034041,-.016881,
-.03164,-.02104,
-.02657,-.01597,
90.*
4,1,16,-.01597,.02657,
-.011114,.02894,
-.005919,.03043,
-.000545,.030995,
.004845,.030619,
.010088,.029313,
.015025,.027115,
.01597,.02657,
.02104,.03164,
.015226,.034813,
.00895,.036928,
.002401,.037921,
-.00422,.037762,
-.010713,.036455,
-.016881,.034041,
-.02104,.03164,
-.01597,.02657,
90.*
%
%ADD39MACRO39*%
%AMMACRO42*
4,1,15,.03682,.01914,
.039584,.012455,
.041146,.005393,
.041457,-.001834,
.040509,-.009005,
.03833,-.015903,
.03682,-.01914,
.04197,-.0243,
.045552,-.016643,
.04775,-.00848,
.048497,-.000059,
.047771,.008363,
.045593,.016531,
.042029,.024197,
.04197,.0243,
.03682,.01914,
90.*
4,1,15,.01914,-.03682,
.012455,-.039584,
.005393,-.041146,
-.001834,-.041457,
-.009005,-.040509,
-.015903,-.03833,
-.01914,-.03682,
-.0243,-.04197,
-.016643,-.045552,
-.00848,-.04775,
-.000059,-.048497,
.008363,-.047771,
.016531,-.045593,
.024197,-.042029,
.0243,-.04197,
.01914,-.03682,
90.*
4,1,15,-.03682,-.01914,
-.039584,-.012455,
-.041146,-.005393,
-.041457,.001834,
-.040509,.009005,
-.03833,.015903,
-.03682,.01914,
-.04197,.0243,
-.045552,.016643,
-.04775,.00848,
-.048497,.000059,
-.047771,-.008363,
-.045593,-.016531,
-.042029,-.024197,
-.04197,-.0243,
-.03682,-.01914,
90.*
4,1,15,-.01914,.03682,
-.012455,.039584,
-.005393,.041146,
.001834,.041457,
.009005,.040509,
.015903,.03833,
.01914,.03682,
.0243,.04197,
.016643,.045552,
.00848,.04775,
.000059,.048497,
-.008363,.047771,
-.016531,.045593,
-.024197,.042029,
-.0243,.04197,
-.01914,.03682,
90.*
%
%ADD42MACRO42*%
%AMMACRO41*
4,1,15,-.03682,.01914,
-.039584,.012455,
-.041146,.005393,
-.041457,-.001834,
-.040509,-.009005,
-.03833,-.015903,
-.03682,-.01914,
-.04197,-.0243,
-.045552,-.016643,
-.04775,-.00848,
-.048497,-.000059,
-.047771,.008363,
-.045593,.016531,
-.042029,.024197,
-.04197,.0243,
-.03682,.01914,
90.*
4,1,15,-.01914,-.03682,
-.012455,-.039584,
-.005393,-.041146,
.001834,-.041457,
.009005,-.040509,
.015903,-.03833,
.01914,-.03682,
.0243,-.04197,
.016643,-.045552,
.00848,-.04775,
.000059,-.048497,
-.008363,-.047771,
-.016531,-.045593,
-.024197,-.042029,
-.0243,-.04197,
-.01914,-.03682,
90.*
4,1,15,.03682,-.01914,
.039584,-.012455,
.041146,-.005393,
.041457,.001834,
.040509,.009005,
.03833,.015903,
.03682,.01914,
.04197,.0243,
.045552,.016643,
.04775,.00848,
.048497,.000059,
.047771,-.008363,
.045593,-.016531,
.042029,-.024197,
.04197,-.0243,
.03682,-.01914,
90.*
4,1,15,.01914,.03682,
.012455,.039584,
.005393,.041146,
-.001834,.041457,
-.009005,.040509,
-.015903,.03833,
-.01914,.03682,
-.0243,.04197,
-.016643,.045552,
-.00848,.04775,
-.000059,.048497,
.008363,.047771,
.016531,.045593,
.024197,.042029,
.0243,.04197,
.01914,.03682,
90.*
%
%ADD41MACRO41*%
%ADD25C,.113*%
%AMMACRO14*
4,1,36,0.0,.005,
.000868,.004924,
.00171,.004698,
.0025,.00433,
.003214,.00383,
.00383,.003214,
.00433,.0025,
.004698,.00171,
.004924,.000868,
.005,0.0,
.004924,-.000868,
.004698,-.00171,
.00433,-.0025,
.00383,-.003214,
.003214,-.00383,
.0025,-.00433,
.00171,-.004698,
.000868,-.004924,
0.0,-.005,
-.000868,-.004924,
-.00171,-.004698,
-.0025,-.00433,
-.003214,-.00383,
-.00383,-.003214,
-.00433,-.0025,
-.004698,-.00171,
-.004924,-.000868,
-.005,0.0,
-.004924,.000868,
-.004698,.00171,
-.00433,.0025,
-.00383,.003214,
-.003214,.00383,
-.0025,.00433,
-.00171,.004698,
-.000868,.004924,
0.0,.005,
180.*
%
%ADD14MACRO14*%
%ADD28C,.115*%
%ADD48C,.116*%
%ADD10C,.125*%
%ADD23C,.155*%
%ADD36C,.256*%
%AMMACRO26*
4,1,36,0.0,.0135,
-.002344,.013295,
-.004617,.012686,
-.00675,.011691,
-.008678,.010342,
-.010342,.008678,
-.011691,.00675,
-.012686,.004617,
-.013295,.002344,
-.0135,0.0,
-.013295,-.002344,
-.012686,-.004617,
-.011691,-.00675,
-.010342,-.008678,
-.008678,-.010342,
-.00675,-.011691,
-.004617,-.012686,
-.002344,-.013295,
0.0,-.0135,
.002344,-.013295,
.004617,-.012686,
.00675,-.011691,
.008678,-.010342,
.010342,-.008678,
.011691,-.00675,
.012686,-.004617,
.013295,-.002344,
.0135,0.0,
.013295,.002344,
.012686,.004617,
.011691,.00675,
.010342,.008678,
.008678,.010342,
.00675,.011691,
.004617,.012686,
.002344,.013295,
0.0,.0135,
270.*
%
%ADD26MACRO26*%
%AMMACRO22*
4,1,36,0.0,.0135,
-.002344,.013295,
-.004617,.012686,
-.00675,.011691,
-.008678,.010342,
-.010342,.008678,
-.011691,.00675,
-.012686,.004617,
-.013295,.002344,
-.0135,0.0,
-.013295,-.002344,
-.012686,-.004617,
-.011691,-.00675,
-.010342,-.008678,
-.008678,-.010342,
-.00675,-.011691,
-.004617,-.012686,
-.002344,-.013295,
0.0,-.0135,
.002344,-.013295,
.004617,-.012686,
.00675,-.011691,
.008678,-.010342,
.010342,-.008678,
.011691,-.00675,
.012686,-.004617,
.013295,-.002344,
.0135,0.0,
.013295,.002344,
.012686,.004617,
.011691,.00675,
.010342,.008678,
.008678,.010342,
.00675,.011691,
.004617,.012686,
.002344,.013295,
0.0,.0135,
180.*
%
%ADD22MACRO22*%
%AMMACRO24*
4,1,36,.0025,0.0,
.002462,.000434,
.002349,.000855,
.002165,.00125,
.001915,.001607,
.001607,.001915,
.00125,.002165,
.000855,.002349,
.000434,.002462,
0.0,.0025,
-.000434,.002462,
-.000855,.002349,
-.00125,.002165,
-.001607,.001915,
-.001915,.001607,
-.002165,.00125,
-.002349,.000855,
-.002462,.000434,
-.0025,0.0,
-.002462,-.000434,
-.002349,-.000855,
-.002165,-.00125,
-.001915,-.001607,
-.001607,-.001915,
-.00125,-.002165,
-.000855,-.002349,
-.000434,-.002462,
0.0,-.0025,
.000434,-.002462,
.000855,-.002349,
.00125,-.002165,
.001607,-.001915,
.001915,-.001607,
.002165,-.00125,
.002349,-.000855,
.002462,-.000434,
.0025,0.0,
90.*
%
%ADD24MACRO24*%
%ADD37C,.187*%
%AMMACRO34*
4,1,36,0.0,.019,
-.003299,.018711,
-.006498,.017854,
-.0095,.016454,
-.012213,.014555,
-.014555,.012213,
-.016454,.0095,
-.017854,.006498,
-.018711,.003299,
-.019,0.0,
-.018711,-.003299,
-.017854,-.006498,
-.016454,-.0095,
-.014555,-.012213,
-.012213,-.014555,
-.0095,-.016454,
-.006498,-.017854,
-.003299,-.018711,
0.0,-.019,
.003299,-.018711,
.006498,-.017854,
.0095,-.016454,
.012213,-.014555,
.014555,-.012213,
.016454,-.0095,
.017854,-.006498,
.018711,-.003299,
.019,0.0,
.018711,.003299,
.017854,.006498,
.016454,.0095,
.014555,.012213,
.012213,.014555,
.0095,.016454,
.006498,.017854,
.003299,.018711,
0.0,.019,
180.*
%
%ADD34MACRO34*%
%AMMACRO17*
4,1,36,.0025,0.0,
.002462,.000434,
.002349,.000855,
.002165,.00125,
.001915,.001607,
.001607,.001915,
.00125,.002165,
.000855,.002349,
.000434,.002462,
0.0,.0025,
-.000434,.002462,
-.000855,.002349,
-.00125,.002165,
-.001607,.001915,
-.001915,.001607,
-.002165,.00125,
-.002349,.000855,
-.002462,.000434,
-.0025,0.0,
-.002462,-.000434,
-.002349,-.000855,
-.002165,-.00125,
-.001915,-.001607,
-.001607,-.001915,
-.00125,-.002165,
-.000855,-.002349,
-.000434,-.002462,
0.0,-.0025,
.000434,-.002462,
.000855,-.002349,
.00125,-.002165,
.001607,-.001915,
.001915,-.001607,
.002165,-.00125,
.002349,-.000855,
.002462,-.000434,
.0025,0.0,
0.0*
%
%ADD17MACRO17*%
%ADD16C,.188*%
%AMMACRO46*
4,1,21,-.0075,-.06379,
-.0075,-.0709,
-.015443,-.068892,
-.022917,-.065536,
-.029695,-.060932,
-.03557,-.055222,
-.040364,-.048578,
-.043932,-.041203,
-.046165,-.03332,
-.046995,-.025169,
-.047,-.0245,
-.047,-.0075,
-.04,-.0075,
-.04,-.0245,
-.039392,-.031446,
-.037588,-.038181,
-.034641,-.0445,
-.030642,-.050211,
-.025712,-.055141,
-.02,-.05914,
-.013681,-.062087,
-.0075,-.06379,
90.*
4,1,21,.0075,-.0709,
.0075,-.06379,
.014209,-.061891,
.020486,-.058856,
.02614,-.054776,
.031001,-.049777,
.034919,-.04401,
.037776,-.03765,
.039486,-.030891,
.04,-.0245,
.04,-.0075,
.047,-.0075,
.047,-.0245,
.046286,-.032662,
.044165,-.040576,
.040703,-.048001,
.036003,-.054713,
.03021,-.060506,
.023499,-.065205,
.016073,-.068668,
.008159,-.070789,
.0075,-.0709,
90.*
4,1,21,-.0075,.0709,
-.0075,.06379,
-.014209,.061891,
-.020486,.058856,
-.02614,.054776,
-.031001,.049777,
-.034919,.04401,
-.037776,.03765,
-.039486,.030891,
-.04,.0245,
-.04,.0075,
-.047,.0075,
-.047,.0245,
-.046286,.032662,
-.044165,.040576,
-.040703,.048001,
-.036003,.054713,
-.03021,.060506,
-.023499,.065205,
-.016073,.068668,
-.008159,.070789,
-.0075,.0709,
90.*
4,1,21,.0075,.06379,
.0075,.0709,
.015443,.068892,
.022917,.065536,
.029695,.060932,
.03557,.055222,
.040364,.048578,
.043932,.041203,
.046165,.03332,
.046995,.025169,
.047,.0245,
.047,.0075,
.04,.0075,
.04,.0245,
.039392,.031446,
.037588,.038181,
.034641,.0445,
.030642,.050211,
.025712,.055141,
.02,.05914,
.013681,.062087,
.0075,.06379,
90.*
%
%ADD46MACRO46*%
%AMMACRO40*
4,1,16,.02657,.01597,
.02894,.011114,
.03043,.005919,
.030995,.000545,
.030619,-.004845,
.029313,-.010088,
.027115,-.015025,
.02657,-.01597,
.03164,-.02104,
.034813,-.015226,
.036928,-.00895,
.037921,-.002401,
.037762,.00422,
.036455,.010713,
.034041,.016881,
.03164,.02104,
.02657,.01597,
270.*
4,1,16,.01597,-.02657,
.011114,-.02894,
.005919,-.03043,
.000545,-.030995,
-.004845,-.030619,
-.010088,-.029313,
-.015025,-.027115,
-.01597,-.02657,
-.02104,-.03164,
-.015226,-.034813,
-.00895,-.036928,
-.002401,-.037921,
.00422,-.037762,
.010713,-.036455,
.016881,-.034041,
.02104,-.03164,
.01597,-.02657,
270.*
4,1,16,-.02657,-.01597,
-.02894,-.011114,
-.03043,-.005919,
-.030995,-.000545,
-.030619,.004845,
-.029313,.010088,
-.027115,.015025,
-.02657,.01597,
-.03164,.02104,
-.034813,.015226,
-.036928,.00895,
-.037921,.002401,
-.037762,-.00422,
-.036455,-.010713,
-.034041,-.016881,
-.03164,-.02104,
-.02657,-.01597,
270.*
4,1,16,-.01597,.02657,
-.011114,.02894,
-.005919,.03043,
-.000545,.030995,
.004845,.030619,
.010088,.029313,
.015025,.027115,
.01597,.02657,
.02104,.03164,
.015226,.034813,
.00895,.036928,
.002401,.037921,
-.00422,.037762,
-.010713,.036455,
-.016881,.034041,
-.02104,.03164,
-.01597,.02657,
270.*
%
%ADD40MACRO40*%
%AMMACRO12*
4,1,18,.10783,.07955,
.120006,.059617,
.128535,.037873,
.133159,.014977,
.133736,-.008373,
.130251,-.031469,
.122807,-.053609,
.111633,-.074119,
.10783,-.07955,
.11284,-.08455,
.125808,-.063671,
.134953,-.040857,
.139997,-.016802,
.140788,.007763,
.137301,.032093,
.129642,.055447,
.118045,.077117,
.11284,.08455,
.10783,.07955,
180.*
4,1,18,.07955,-.10783,
.059617,-.120006,
.037873,-.128535,
.014977,-.133159,
-.008373,-.133736,
-.031469,-.130251,
-.053609,-.122807,
-.074119,-.111633,
-.07955,-.10783,
-.08455,-.11284,
-.063671,-.125808,
-.040857,-.134953,
-.016802,-.139997,
.007763,-.140788,
.032093,-.137301,
.055447,-.129642,
.077117,-.118045,
.08455,-.11284,
.07955,-.10783,
180.*
4,1,18,-.10783,-.07955,
-.120006,-.059617,
-.128535,-.037873,
-.133159,-.014977,
-.133736,.008373,
-.130251,.031469,
-.122807,.053609,
-.111633,.074119,
-.10783,.07955,
-.11284,.08455,
-.125808,.063671,
-.134953,.040857,
-.139997,.016802,
-.140788,-.007763,
-.137301,-.032093,
-.129642,-.055447,
-.118045,-.077117,
-.11284,-.08455,
-.10783,-.07955,
180.*
4,1,18,-.07955,.10783,
-.059617,.120006,
-.037873,.128535,
-.014977,.133159,
.008373,.133736,
.031469,.130251,
.053609,.122807,
.074119,.111633,
.07955,.10783,
.08455,.11284,
.063671,.125808,
.040857,.134953,
.016802,.139997,
-.007763,.140788,
-.032093,.137301,
-.055447,.129642,
-.077117,.118045,
-.08455,.11284,
-.07955,.10783,
180.*
%
%ADD12MACRO12*%
%AMMACRO31*
4,1,15,.03682,.01914,
.039584,.012455,
.041146,.005393,
.041457,-.001834,
.040509,-.009005,
.03833,-.015903,
.03682,-.01914,
.04197,-.0243,
.045552,-.016643,
.04775,-.00848,
.048497,-.000059,
.047771,.008363,
.045593,.016531,
.042029,.024197,
.04197,.0243,
.03682,.01914,
270.*
4,1,15,.01914,-.03682,
.012455,-.039584,
.005393,-.041146,
-.001834,-.041457,
-.009005,-.040509,
-.015903,-.03833,
-.01914,-.03682,
-.0243,-.04197,
-.016643,-.045552,
-.00848,-.04775,
-.000059,-.048497,
.008363,-.047771,
.016531,-.045593,
.024197,-.042029,
.0243,-.04197,
.01914,-.03682,
270.*
4,1,15,-.03682,-.01914,
-.039584,-.012455,
-.041146,-.005393,
-.041457,.001834,
-.040509,.009005,
-.03833,.015903,
-.03682,.01914,
-.04197,.0243,
-.045552,.016643,
-.04775,.00848,
-.048497,.000059,
-.047771,-.008363,
-.045593,-.016531,
-.042029,-.024197,
-.04197,-.0243,
-.03682,-.01914,
270.*
4,1,15,-.01914,.03682,
-.012455,.039584,
-.005393,.041146,
.001834,.041457,
.009005,.040509,
.015903,.03833,
.01914,.03682,
.0243,.04197,
.016643,.045552,
.00848,.04775,
.000059,.048497,
-.008363,.047771,
-.016531,.045593,
-.024197,.042029,
-.0243,.04197,
-.01914,.03682,
270.*
%
%ADD31MACRO31*%
%AMMACRO33*
4,1,15,-.03682,.01914,
-.039584,.012455,
-.041146,.005393,
-.041457,-.001834,
-.040509,-.009005,
-.03833,-.015903,
-.03682,-.01914,
-.04197,-.0243,
-.045552,-.016643,
-.04775,-.00848,
-.048497,-.000059,
-.047771,.008363,
-.045593,.016531,
-.042029,.024197,
-.04197,.0243,
-.03682,.01914,
270.*
4,1,15,-.01914,-.03682,
-.012455,-.039584,
-.005393,-.041146,
.001834,-.041457,
.009005,-.040509,
.015903,-.03833,
.01914,-.03682,
.0243,-.04197,
.016643,-.045552,
.00848,-.04775,
.000059,-.048497,
-.008363,-.047771,
-.016531,-.045593,
-.024197,-.042029,
-.0243,-.04197,
-.01914,-.03682,
270.*
4,1,15,.03682,-.01914,
.039584,-.012455,
.041146,-.005393,
.041457,.001834,
.040509,.009005,
.03833,.015903,
.03682,.01914,
.04197,.0243,
.045552,.016643,
.04775,.00848,
.048497,.000059,
.047771,-.008363,
.045593,-.016531,
.042029,-.024197,
.04197,-.0243,
.03682,-.01914,
270.*
4,1,15,.01914,.03682,
.012455,.039584,
.005393,.041146,
-.001834,.041457,
-.009005,.040509,
-.015903,.03833,
-.01914,.03682,
-.0243,.04197,
-.016643,.045552,
-.00848,.04775,
-.000059,.048497,
.008363,.047771,
.016531,.045593,
.024197,.042029,
.0243,.04197,
.01914,.03682,
270.*
%
%ADD33MACRO33*%
%ADD50C,.02*%
%ADD51C,.006*%
%ADD57C,.07006*%
%ADD59C,.08008*%
%ADD60C,.09558*%
%ADD64C,.11022*%
%ADD58C,.12006*%
%ADD62C,.185*%
%ADD55C,.1175*%
%ADD65C,.12606*%
%ADD56O,.40438X.60123*%
%ADD54C,.1195*%
%ADD53C,.16506*%
%ADD63C,.28606*%
%ADD61C,.45382*%
%ADD52C,.19806*%
G75*
%LPD*%
G75*
G36*
G01X-457143Y-1211429D02*
X4308572D01*
Y2242857D01*
X-457143D01*
Y-1211429D01*
G37*
%LPC*%
G75*
G36*
G01X76695Y619228D02*
X86605D01*
G02X86747Y619169I0J-200D01*
G01X89329Y616587D01*
G02X89388Y616445I-141J-142D01*
G01Y177012D01*
G03X89974Y175598I1999J0D01*
G01X131090Y134482D01*
X131120Y134398D01*
X131115Y134353D01*
G03X131098Y134000I3485J-345D01*
G03X134600Y130498I3502J0D01*
G03X134962Y130516I7J3502D01*
G02X135112Y130470I21J-199D01*
G03X136400Y130000I1288J1530D01*
G01X227015D01*
G02X227157Y129941I0J-200D01*
G01X227534Y129564D01*
X227564Y129489D01*
X227562Y129447D01*
G03X227561Y129365I2999J-78D01*
G01Y88313D01*
G02X227461Y88140I-200J0D01*
G03X223348Y81000I4139J-7139D01*
G03X227461Y73860I8252J-1D01*
G02X227561Y73687I-100J-173D01*
G01Y6936D01*
G02X227502Y6794I-200J0D01*
G01X224767Y4059D01*
G02X224625Y4000I-142J141D01*
G01X222653D01*
G02X222507Y4064I1J200D01*
G03X220305I-1101J-1023D01*
G02X220159Y4000I-147J136D01*
G01X202653D01*
G02X202507Y4064I1J200D01*
G03X200305I-1101J-1023D01*
G02X200159Y4000I-147J136D01*
G01X182653D01*
G02X182507Y4064I1J200D01*
G03X180305I-1101J-1023D01*
G02X180159Y4000I-147J136D01*
G01X162653D01*
G02X162507Y4064I1J200D01*
G03X160305I-1101J-1023D01*
G02X160159Y4000I-147J136D01*
G01X142653D01*
G02X142507Y4064I1J200D01*
G03X140305I-1101J-1023D01*
G02X140159Y4000I-147J136D01*
G01X122653D01*
G02X122507Y4064I1J200D01*
G03X120305I-1101J-1023D01*
G02X120159Y4000I-147J136D01*
G01X102653D01*
G02X102507Y4064I1J200D01*
G03X100305I-1101J-1023D01*
G02X100159Y4000I-147J136D01*
G01X82653D01*
G02X82507Y4064I1J200D01*
G03X80305I-1101J-1023D01*
G02X80159Y4000I-147J136D01*
G01X31930D01*
G02X31786Y4061I0J200D01*
G03X29632I-1077J-1047D01*
G02X29488Y4000I-144J139D01*
G01X19685D01*
G02X12068Y5974I1J15685D01*
G02X11968Y6111I96J175D01*
G03X10493Y7332I-1475J-280D01*
G03X10179Y7299I-1J-1502D01*
G02X10013Y7337I-43J195D01*
G02X4000Y19685I9672J12348D01*
G01Y22705D01*
G02X4061Y22849I200J0D01*
G03Y25011I-1043J1081D01*
G02X4000Y25155I139J144D01*
G01Y42705D01*
G02X4061Y42849I200J0D01*
G03Y45011I-1043J1081D01*
G02X4000Y45155I139J144D01*
G01Y62705D01*
G02X4061Y62849I200J0D01*
G03Y65011I-1043J1081D01*
G02X4000Y65155I139J144D01*
G01Y82705D01*
G02X4061Y82849I200J0D01*
G03Y85011I-1043J1081D01*
G02X4000Y85155I139J144D01*
G01Y102705D01*
G02X4061Y102849I200J0D01*
G03Y105011I-1043J1081D01*
G02X4000Y105155I139J144D01*
G01Y122705D01*
G02X4061Y122849I200J0D01*
G03Y125011I-1043J1081D01*
G02X4000Y125155I139J144D01*
G01Y142705D01*
G02X4061Y142849I200J0D01*
G03Y145011I-1043J1081D01*
G02X4000Y145155I139J144D01*
G01Y162705D01*
G02X4061Y162849I200J0D01*
G03Y165011I-1043J1081D01*
G02X4000Y165155I139J144D01*
G01Y182705D01*
G02X4061Y182849I200J0D01*
G03Y185011I-1043J1081D01*
G02X4000Y185155I139J144D01*
G01Y202705D01*
G02X4061Y202849I200J0D01*
G03Y205011I-1043J1081D01*
G02X4000Y205155I139J144D01*
G01Y222705D01*
G02X4061Y222849I200J0D01*
G03Y225011I-1043J1081D01*
G02X4000Y225155I139J144D01*
G01Y242705D01*
G02X4061Y242849I200J0D01*
G03Y245011I-1043J1081D01*
G02X4000Y245155I139J144D01*
G01Y262705D01*
G02X4061Y262849I200J0D01*
G03Y265011I-1043J1081D01*
G02X4000Y265155I139J144D01*
G01Y282705D01*
G02X4061Y282849I200J0D01*
G03Y285011I-1043J1081D01*
G02X4000Y285155I139J144D01*
G01Y302705D01*
G02X4061Y302849I200J0D01*
G03Y305011I-1043J1081D01*
G02X4000Y305155I139J144D01*
G01Y322705D01*
G02X4061Y322849I200J0D01*
G03Y325011I-1043J1081D01*
G02X4000Y325155I139J144D01*
G01Y342705D01*
G02X4061Y342849I200J0D01*
G03Y345011I-1043J1081D01*
G02X4000Y345155I139J144D01*
G01Y362705D01*
G02X4061Y362849I200J0D01*
G03Y365011I-1043J1081D01*
G02X4000Y365155I139J144D01*
G01Y382705D01*
G02X4061Y382849I200J0D01*
G03Y385011I-1043J1081D01*
G02X4000Y385155I139J144D01*
G01Y402705D01*
G02X4061Y402849I200J0D01*
G03Y405011I-1043J1081D01*
G02X4000Y405155I139J144D01*
G01Y422705D01*
G02X4061Y422849I200J0D01*
G03Y425011I-1043J1081D01*
G02X4000Y425155I139J144D01*
G01Y442705D01*
G02X4061Y442849I200J0D01*
G03Y445011I-1043J1081D01*
G02X4000Y445155I139J144D01*
G01Y462705D01*
G02X4061Y462849I200J0D01*
G03Y465011I-1043J1081D01*
G02X4000Y465155I139J144D01*
G01Y482705D01*
G02X4061Y482849I200J0D01*
G03Y485011I-1043J1081D01*
G02X4000Y485155I139J144D01*
G01Y502705D01*
G02X4061Y502849I200J0D01*
G03Y505011I-1043J1081D01*
G02X4000Y505155I139J144D01*
G01Y522705D01*
G02X4061Y522849I200J0D01*
G03Y525011I-1043J1081D01*
G02X4000Y525155I139J144D01*
G01Y542705D01*
G02X4061Y542849I200J0D01*
G03Y545011I-1043J1081D01*
G02X4000Y545155I139J144D01*
G01Y562705D01*
G02X4061Y562849I200J0D01*
G03Y565011I-1043J1081D01*
G02X4000Y565155I139J144D01*
G01Y582705D01*
G02X4061Y582849I200J0D01*
G03Y585011I-1043J1081D01*
G02X4000Y585155I139J144D01*
G01Y602705D01*
G02X4061Y602849I200J0D01*
G03X4520Y603930I-1043J1081D01*
G03X4128Y604942I-1502J0D01*
G02X4077Y605096I148J134D01*
G02X14735Y618427I15608J-1553D01*
G02X14898Y618410I63J-190D01*
G03X15642Y618213I744J1306D01*
G03X16913Y618914I0J1503D01*
G02X17048Y619005I170J-106D01*
G02X19685Y619228I2635J-15462D01*
G01X34215D01*
G02X34361Y619165I0J-200D01*
G03X36549I1094J1029D01*
G02X36695Y619228I146J-137D01*
G01X54215D01*
G02X54361Y619165I0J-200D01*
G03X56549I1094J1029D01*
G02X56695Y619228I146J-137D01*
G01X74215D01*
G02X74361Y619165I0J-200D01*
G03X76549I1094J1029D01*
G02X76695Y619228I146J-137D01*
G37*
G36*
G01X1866142Y783851D02*
G02X1872016Y777977I0J-5874D01*
G01Y534528D01*
G02X1866142Y528654I-5874J0D01*
G01X1751968D01*
G02X1742157Y538465I1J9811D01*
G01Y603543D01*
G03X1712598Y633102I-29559J0D01*
G01X1640064D01*
G02X1630253Y642913I0J9811D01*
G01Y738607D01*
G03X1620379Y748481I-9874J0D01*
G01X1383858D01*
G03X1373984Y738607I0J-9874D01*
G01Y435039D01*
G02X1354331Y415386I-19653J0D01*
G01X1154764D01*
G02X1148890Y421260I0J5874D01*
G01Y479449D01*
G03X1135079Y493260I-13811J0D01*
G01X550827D01*
G03X537016Y479449I0J-13811D01*
G01Y421260D01*
G02X531142Y415386I-5874J0D01*
G01X377952D01*
G02X358299Y435039I0J19653D01*
G01Y738607D01*
G03X348425Y748481I-9874J0D01*
G01X111905D01*
G03X102031Y738607I0J-9874D01*
G01Y642913D01*
G02X92220Y633102I-9811J0D01*
G01X7874D01*
G02X2000Y638976I0J5874D01*
G01Y777977D01*
G02X7874Y783851I5874J0D01*
G01X1866142D01*
G37*
G36*
G01X467291Y274141D02*
X463668Y270518D01*
G02X463526Y270459I-142J141D01*
G01X441767D01*
G03X440353Y269873I0J-1999D01*
G01X437204Y266724D01*
G03X436618Y265310I1413J-1414D01*
G01Y253345D01*
G03X437204Y251931I1999J0D01*
G01X439723Y249412D01*
G03X441137Y248826I1414J1413D01*
G01X463780D01*
G02X463922Y248767I0J-200D01*
G01X466914Y245775D01*
G02X466973Y245633I-141J-142D01*
G01Y229696D01*
G02X466914Y229554I-200J0D01*
G01X464426Y227066D01*
G02X464284Y227007I-142J141D01*
G01X440886D01*
G03X439472Y226421I0J-1999D01*
G01X437205Y224154D01*
G03X436619Y222740I1413J-1414D01*
G01Y219436D01*
G03X436952Y218331I2000J0D01*
G01X436977Y218294D01*
X436990Y218206D01*
X436886Y217867D01*
G02X436770Y217740I-191J58D01*
G03X434598Y214500I1331J-3240D01*
G03X441602I3502J0D01*
G01Y214526D01*
G02X441802Y214726I200J0D01*
G01X481400D01*
G02X481600Y214526I0J-200D01*
G01Y182700D01*
G02X481400Y182500I-200J0D01*
G01X441057D01*
G03X439643Y181914I0J-1999D01*
G01X437532Y179803D01*
G03X436946Y178389I1413J-1414D01*
G01Y173855D01*
G03X436979Y173496I2000J3D01*
G02X436853Y173273I-197J-36D01*
G03X434598Y170000I1248J-3273D01*
G03X438100Y166498I3502J0D01*
G03X441475Y169063I0J3503D01*
G01Y169064D01*
G02X441667Y169210I193J-54D01*
G01X464232D01*
G02X464374Y169151I0J-200D01*
G01X468500Y165025D01*
G02X468559Y164883I-141J-142D01*
G01Y142523D01*
G02X468500Y142381I-200J0D01*
G01X467019Y140900D01*
G02X466877Y140841I-142J141D01*
G01X441464D01*
G03X440050Y140255I0J-1999D01*
G01X437406Y137611D01*
G03X436820Y136197I1413J-1414D01*
G01Y120706D01*
G03X437406Y119292I1999J0D01*
G01X440052Y116646D01*
G03X441466Y116060I1414J1413D01*
G01X467257D01*
G02X467399Y116001I0J-200D01*
G01X467998Y115402D01*
G02X468057Y115260I-141J-142D01*
G01Y97686D01*
G02X467998Y97544I-200J0D01*
G01X466895Y96441D01*
G02X466753Y96382I-142J141D01*
G01X441089D01*
G03X439675Y95796I0J-1999D01*
G01X437659Y93780D01*
G03X437073Y92366I1413J-1414D01*
G01Y75994D01*
G03X437659Y74580I1999J0D01*
G01X439927Y72312D01*
G03X441341Y71726I1414J1413D01*
G01X481400D01*
G02X481600Y71526I0J-200D01*
G01Y36633D01*
G02X481400Y36433I-200J0D01*
G01X387878D01*
G02X387736Y36492I0J200D01*
G01X290814Y133414D01*
G03X289400Y134000I-1414J-1413D01*
G01X138296D01*
G02X138097Y134188I1J200D01*
G01Y134189D01*
G03X134600Y137502I-3497J-189D01*
G01X134599D01*
G03X133919Y137435I2J-3502D01*
G01X133917D01*
G02X133738Y137490I-38J196D01*
G01X93447Y177781D01*
G02X93388Y177923I141J142D01*
G01Y616445D01*
G02X93447Y616587I200J0D01*
G01X93856Y616996D01*
X93977Y617018D01*
X94034Y616993D01*
G03X95454Y616692I1420J3201D01*
G01X95455D01*
G03X98779Y619091I0J3502D01*
G01X98799Y619152D01*
X98904Y619228D01*
X102364D01*
G03X112340Y621432I-1J23684D01*
G01X112425Y621451D01*
X112559Y621399D01*
G03X114923Y620480I2364J2581D01*
G03X118425Y623982I0J3502D01*
G03X118222Y625156I-3502J-1D01*
G01X118210Y625223D01*
X118276Y625371D01*
G03X125158Y636484I-15914J17542D01*
G01X125326Y636629D01*
G03X128403Y640105I-425J3476D01*
G03X126174Y643367I-3501J0D01*
G02X126047Y643553I73J186D01*
G01Y656102D01*
G02X141732Y671787I15685J0D01*
G01X151274D01*
G02X151463Y671652I0J-200D01*
G01Y671651D01*
G03X153511Y669514I3315J1128D01*
G01X153565Y669493D01*
X153634Y669401D01*
X153668Y668986D01*
G02X153570Y668797I-199J-17D01*
G03X151226Y664685I2435J-4112D01*
G03X152900Y661052I4779J0D01*
G02X152970Y660900I-130J-152D01*
G01Y660596D01*
G02X152900Y660444I-200J0D01*
G03Y653178I3105J-3633D01*
G02X152970Y653026I-130J-152D01*
G01Y652722D01*
G02X152900Y652570I-200J0D01*
G03Y645304I3105J-3633D01*
G02X152970Y645152I-130J-152D01*
G01Y644848D01*
G02X152900Y644696I-200J0D01*
G03Y637430I3105J-3633D01*
G02X152970Y637278I-130J-152D01*
G01Y636974D01*
G02X152900Y636822I-200J0D01*
G03Y629556I3105J-3633D01*
G02X152970Y629404I-130J-152D01*
G01Y629100D01*
G02X152900Y628948I-200J0D01*
G03Y621682I3105J-3633D01*
G02X152970Y621530I-130J-152D01*
G01Y621226D01*
G02X152900Y621074I-200J0D01*
G03Y613808I3105J-3633D01*
G02X152970Y613656I-130J-152D01*
G01Y613352D01*
G02X152900Y613200I-200J0D01*
G03Y605934I3105J-3633D01*
G02X152970Y605782I-130J-152D01*
G01Y605478D01*
G02X152900Y605326I-200J0D01*
G03X151226Y601693I3105J-3633D01*
G03X156004Y596914I4779J0D01*
G03X159637Y598589I-1J4779D01*
G02X159789Y598659I152J-130D01*
G01X160093D01*
G02X160245Y598589I0J-200D01*
G03X163878Y596914I3634J3104D01*
G03X168656Y601691I0J4778D01*
G01Y601693D01*
G03X166982Y605326I-4779J0D01*
G02X166912Y605478I130J152D01*
G01Y605782D01*
G02X166982Y605934I200J0D01*
G03Y613200I-3105J3633D01*
G02X166912Y613352I130J152D01*
G01Y613656D01*
G02X166982Y613808I200J0D01*
G03Y621074I-3105J3633D01*
G02X166912Y621226I130J152D01*
G01Y621530D01*
G02X166982Y621682I200J0D01*
G03Y628948I-3105J3633D01*
G02X166912Y629100I130J152D01*
G01Y629404D01*
G02X166982Y629556I200J0D01*
G03Y636822I-3105J3633D01*
G02X166912Y636974I130J152D01*
G01Y637278D01*
G02X166982Y637430I200J0D01*
G03Y644696I-3105J3633D01*
G02X166912Y644848I130J152D01*
G01Y645152D01*
G02X166982Y645304I200J0D01*
G03Y652570I-3105J3633D01*
G02X166912Y652722I130J152D01*
G01Y653026D01*
G02X166982Y653178I200J0D01*
G03Y660444I-3105J3633D01*
G02X166912Y660596I130J152D01*
G01Y660900D01*
G02X166982Y661052I200J0D01*
G03X168656Y664685I-3105J3633D01*
G03X163878Y669464I-4779J0D01*
G03X160245Y667789I1J-4779D01*
G02X160093Y667719I-152J130D01*
G01X159789D01*
G02X159637Y667789I0J200D01*
G03X157111Y669334I-3634J-3103D01*
G01X156962Y669485D01*
X156884Y669836D01*
G02X156955Y670036I195J43D01*
G03X158093Y671651I-2177J2743D01*
G01Y671652D01*
G02X158282Y671787I189J-65D01*
G01X171274D01*
G02X171463Y671652I0J-200D01*
G01Y671651D01*
G03X178093I3315J1127D01*
G01Y671652D01*
G02X178282Y671787I189J-65D01*
G01X191274D01*
G02X191463Y671652I0J-200D01*
G01Y671651D01*
G03X192451Y670162I3315J1128D01*
G01X192498Y670120D01*
X192527Y669999D01*
X192369Y669591D01*
G02X192178Y669463I-187J72D01*
G01X192177D01*
G03X192127Y669464I-121J-4777D01*
G01X192125D01*
G03X187348Y664687I1J-4778D01*
G01Y664685D01*
G03X189022Y661052I4779J0D01*
G02X189092Y660900I-130J-152D01*
G01Y660596D01*
G02X189022Y660444I-200J0D01*
G03Y653178I3105J-3633D01*
G02X189092Y653026I-130J-152D01*
G01Y652722D01*
G02X189022Y652570I-200J0D01*
G03X187348Y648937I3105J-3633D01*
G03X192126Y644158I4779J0D01*
G03X195759Y645833I-1J4779D01*
G02X195911Y645903I152J-130D01*
G01X196215D01*
G02X196367Y645833I0J-200D01*
G03X200000Y644158I3634J3104D01*
G03X204778Y648935I0J4778D01*
G01Y648937D01*
G03X203104Y652570I-4779J0D01*
G02X203034Y652722I130J152D01*
G01Y653026D01*
G02X203104Y653178I200J0D01*
G03Y660444I-3105J3633D01*
G02X203034Y660596I130J152D01*
G01Y660900D01*
G02X203104Y661052I200J0D01*
G03X204778Y664685I-3105J3633D01*
G03X200000Y669464I-4779J0D01*
G03X196367Y667789I1J-4779D01*
G02X196215Y667719I-152J130D01*
G01X195911D01*
G02X195759Y667789I0J200D01*
G03X194910Y668569I-3634J-3103D01*
G02X194833Y668784I116J163D01*
G01X194947Y669206D01*
X195043Y669286D01*
X195105Y669292D01*
G03X198093Y671651I-327J3487D01*
G01Y671652D01*
G02X198282Y671787I189J-65D01*
G01X211274D01*
G02X211463Y671652I0J-200D01*
G01Y671651D01*
G03X213377Y669569I3316J1127D01*
G01X213378D01*
G02X213497Y669395I-81J-183D01*
G01X213518Y668981D01*
X213462Y668881D01*
X213413Y668854D01*
G03X210970Y664685I2336J-4169D01*
G03X212644Y661052I4779J0D01*
G02X212714Y660900I-130J-152D01*
G01Y660596D01*
G02X212644Y660444I-200J0D01*
G03Y653178I3105J-3633D01*
G02X212714Y653026I-130J-152D01*
G01Y652722D01*
G02X212644Y652570I-200J0D01*
G03X210970Y648937I3105J-3633D01*
G03X215748Y644158I4779J0D01*
G03X219381Y645833I-1J4779D01*
G02X219533Y645903I152J-130D01*
G01X219837D01*
G02X219989Y645833I0J-200D01*
G03X223622Y644158I3634J3104D01*
G03X228400Y648935I0J4778D01*
G01Y648937D01*
G03X226726Y652570I-4779J0D01*
G02X226656Y652722I130J152D01*
G01Y653026D01*
G02X226726Y653178I200J0D01*
G03Y660444I-3105J3633D01*
G02X226656Y660596I130J152D01*
G01Y660900D01*
G02X226726Y661052I200J0D01*
G03X228400Y664685I-3105J3633D01*
G03X223622Y669464I-4779J0D01*
G03X219989Y667789I1J-4779D01*
G02X219837Y667719I-152J130D01*
G01X219533D01*
G02X219381Y667789I0J200D01*
G03X217032Y669288I-3633J-3104D01*
G01X216978Y669303D01*
X216900Y669387D01*
X216812Y669850D01*
X216852Y669956D01*
X216898Y669991D01*
G03X218093Y671651I-2121J2787D01*
G01Y671652D01*
G02X218282Y671787I189J-65D01*
G01X231274D01*
G02X231463Y671652I0J-200D01*
G01Y671651D01*
G03X238093I3315J1127D01*
G01Y671652D01*
G02X238282Y671787I189J-65D01*
G01X251274D01*
G02X251463Y671652I0J-200D01*
G01Y671651D01*
G03X253458Y669535I3316J1127D01*
G02X253583Y669363I-75J-186D01*
G01X253607Y669006D01*
G02X253509Y668819I-199J-15D01*
G01X253508D01*
G03X252273Y667789I2400J-4133D01*
G02X252121Y667719I-152J130D01*
G01X251817D01*
G02X251665Y667789I0J200D01*
G03X248032Y669464I-3634J-3104D01*
G03X243254Y664687I0J-4778D01*
G01Y664685D01*
G03X244928Y661052I4779J0D01*
G02X244998Y660900I-130J-152D01*
G01Y660596D01*
G02X244928Y660444I-200J0D01*
G03Y653178I3105J-3633D01*
G02X244998Y653026I-130J-152D01*
G01Y652722D01*
G02X244928Y652570I-200J0D01*
G03X243254Y648937I3105J-3633D01*
G03X248032Y644158I4779J0D01*
G03X251665Y645833I-1J4779D01*
G02X251817Y645903I152J-130D01*
G01X252121D01*
G02X252273Y645833I0J-200D01*
G03X255906Y644158I3634J3104D01*
G03X260684Y648935I0J4778D01*
G01Y648937D01*
G03X259010Y652570I-4779J0D01*
G02X258940Y652722I130J152D01*
G01Y653026D01*
G02X259010Y653178I200J0D01*
G03X260222Y654759I-3103J3634D01*
G02X260345Y654865I181J-86D01*
G01X260627Y654950D01*
G02X260787Y654931I58J-191D01*
G03X266773I2993J5030D01*
G02X266933Y654950I102J-172D01*
G01X267215Y654865D01*
G02X267338Y654759I-58J-192D01*
G03X268550Y653178I4315J2053D01*
G02X268620Y653026I-130J-152D01*
G01Y652722D01*
G02X268550Y652570I-200J0D01*
G03X266876Y648937I3105J-3633D01*
G03X271654Y644158I4779J0D01*
G03X275287Y645833I-1J4779D01*
G02X275439Y645903I152J-130D01*
G01X275743D01*
G02X275895Y645833I0J-200D01*
G03X279528Y644158I3634J3104D01*
G03X284306Y648935I0J4778D01*
G01Y648937D01*
G03X282632Y652570I-4779J0D01*
G02X282562Y652722I130J152D01*
G01Y653026D01*
G02X282632Y653178I200J0D01*
G03Y660444I-3105J3633D01*
G02X282562Y660596I130J152D01*
G01Y660900D01*
G02X282632Y661052I200J0D01*
G03X284306Y664685I-3105J3633D01*
G03X279528Y669464I-4779J0D01*
G03X275895Y667789I1J-4779D01*
G02X275743Y667719I-152J130D01*
G01X275439D01*
G02X275287Y667789I0J200D01*
G03X274458Y668554I-3632J-3105D01*
G01X274405Y668593D01*
X274365Y668717D01*
X274529Y669205D01*
X274636Y669280D01*
X274702Y669278D01*
G03X274778Y669277I84J3501D01*
G03X278093Y671651I0J3501D01*
G01Y671652D01*
G02X278282Y671787I189J-65D01*
G01X291274D01*
G02X291463Y671652I0J-200D01*
G01Y671651D01*
G03X293155Y669676I3315J1128D01*
G01X293206Y669649D01*
X293262Y669554D01*
X293258Y669140D01*
G02X293148Y668963I-200J2D01*
G01X293147D01*
G03X290498Y664685I2130J-4278D01*
G03X292172Y661052I4779J0D01*
G02X292242Y660900I-130J-152D01*
G01Y660596D01*
G02X292172Y660444I-200J0D01*
G03Y653178I3105J-3633D01*
G02X292242Y653026I-130J-152D01*
G01Y652722D01*
G02X292172Y652570I-200J0D01*
G03X290498Y648937I3105J-3633D01*
G03X295276Y644158I4779J0D01*
G03X298909Y645833I-1J4779D01*
G02X299061Y645903I152J-130D01*
G01X299365D01*
G02X299517Y645833I0J-200D01*
G03X303150Y644158I3634J3104D01*
G03X307928Y648935I0J4778D01*
G01Y648937D01*
G03X306254Y652570I-4779J0D01*
G02X306184Y652722I130J152D01*
G01Y653026D01*
G02X306254Y653178I200J0D01*
G03Y660444I-3105J3633D01*
G02X306184Y660596I130J152D01*
G01Y660900D01*
G02X306254Y661052I200J0D01*
G03X307899Y664153I-3104J3633D01*
G02X308054Y664326I199J-22D01*
G01X308424Y664408D01*
G02X308637Y664318I43J-195D01*
G02X310961Y656102I-13361J-8216D01*
G01Y654961D01*
X310887Y654858D01*
X310826Y654837D01*
G03Y648207I1130J-3315D01*
G01X310887Y648186D01*
X310961Y648083D01*
Y635039D01*
G03X326772Y619228I15811J0D01*
G01X327783D01*
X327890Y619146D01*
X327908Y619081D01*
G03X331285Y616506I3377J927D01*
G03X334207Y618078I0J3502D01*
G02X334447Y618154I167J-110D01*
G02X338990Y615416I-5709J-14610D01*
G02X339036Y615170I-130J-152D01*
G03X338617Y613510I3082J-1661D01*
G03X342119Y610008I3502J0D01*
G01X342120D01*
G03X342826Y610080I0J3502D01*
G01X342867Y610084D01*
G02X343049Y609966I0J-200D01*
G02X344425Y603543I-14309J-6424D01*
G01Y598523D01*
G02X344289Y598334I-200J0D01*
G03Y591700I1123J-3317D01*
G02X344425Y591511I-64J-189D01*
G01Y578523D01*
G02X344289Y578334I-200J0D01*
G03Y571700I1123J-3317D01*
G02X344425Y571511I-64J-189D01*
G01Y558523D01*
G02X344289Y558334I-200J0D01*
G03Y551700I1123J-3317D01*
G02X344425Y551511I-64J-189D01*
G01Y538523D01*
G02X344289Y538334I-200J0D01*
G03Y531700I1123J-3317D01*
G02X344425Y531511I-64J-189D01*
G01Y518523D01*
G02X344289Y518334I-200J0D01*
G03Y511700I1123J-3317D01*
G02X344425Y511511I-64J-189D01*
G01Y498523D01*
G02X344289Y498334I-200J0D01*
G03Y491700I1123J-3317D01*
G02X344425Y491511I-64J-189D01*
G01Y478523D01*
G02X344289Y478334I-200J0D01*
G03Y471700I1123J-3317D01*
G02X344425Y471511I-64J-189D01*
G01Y458523D01*
G02X344289Y458334I-200J0D01*
G03Y451700I1123J-3317D01*
G02X344425Y451511I-64J-189D01*
G01Y438523D01*
G02X344289Y438334I-200J0D01*
G03X341910Y435017I1123J-3317D01*
G03X344470Y431644I3502J0D01*
G01X344615Y431472D01*
G03X344646Y431196I33333J3604D01*
G03X344809Y429977I33308J3833D01*
G03X344912Y429343I33144J5059D01*
G03X346168Y424369I33040J5697D01*
G03X347521Y420968I31783J10674D01*
G02X347484Y420746I-182J-84D01*
G03X346522Y418335I2540J-2411D01*
G03X350024Y414833I3502J0D01*
G03X350947Y414957I-1J3503D01*
G02X351160Y414884I53J-193D01*
G03X352189Y413584I26795J20152D01*
G03X352448Y413276I25790J21424D01*
G01X352476Y413244D01*
X352499Y413217D01*
X352506Y413209D01*
X352507Y413208D01*
G03X354006Y411573I25449J21827D01*
G03X355266Y410353I23944J23469D01*
G03X358642Y407631I22688J24685D01*
G01X358727Y407468D01*
X358721Y407421D01*
G03X358625Y406608I3406J-814D01*
G03X362127Y403106I3502J0D01*
G03X364614Y404142I0J3503D01*
G02X364834Y404186I142J-140D01*
G03X365403Y403949I13175J30830D01*
G01X365405D01*
X365415Y403944D01*
X365417D01*
G03X366056Y403693I12577J31079D01*
G03X366584Y403498I11879J31353D01*
G03X367070Y403327I11371J31540D01*
G01X367084Y403322D01*
G03X367126Y403308I10623J31799D01*
G01X367134Y403305D01*
G03X368155Y402975I10821J31734D01*
G03X369032Y402720I9799J32064D01*
G03X371832Y402075I8919J32319D01*
G03X373832Y401766I6117J32965D01*
G03X376172Y401559I4123J33273D01*
G02X376352Y401422I-10J-200D01*
G03X379680Y399008I3328J1087D01*
G03X382994Y401377I0J3502D01*
G01X383015Y401438D01*
X383118Y401512D01*
X396242D01*
X396345Y401438D01*
X396366Y401377D01*
G03X402994I3314J1133D01*
G01X403015Y401438D01*
X403118Y401512D01*
X416242D01*
X416345Y401438D01*
X416366Y401377D01*
G03X422994I3314J1133D01*
G01X423015Y401438D01*
X423118Y401512D01*
X436242D01*
X436345Y401438D01*
X436366Y401377D01*
G03X442994I3314J1133D01*
G01X443015Y401438D01*
X443118Y401512D01*
X449396D01*
G02X449596Y401312I0J-200D01*
G01Y329253D01*
G02X449537Y329111I-200J0D01*
G01X436257Y315831D01*
G03X435671Y314417I1413J-1414D01*
G01Y295981D01*
G03X436257Y294567I1999J0D01*
G01X438338Y292486D01*
G03X439752Y291900I1414J1413D01*
G01X464534D01*
G02X464676Y291841I0J-200D01*
G01X467291Y289226D01*
G02X467350Y289084I-141J-142D01*
G01Y274283D01*
G02X467291Y274141I-200J0D01*
G37*
G36*
G01X1598011Y303500D02*
X1859989D01*
G02X1860129Y303443I0J-200D01*
G01X1860130Y303442D01*
X1861341Y302231D01*
G02X1861343Y302229I-140J-142D01*
G02X1861400Y302089I-143J-140D01*
G01Y268911D01*
G02X1861341Y268769I-200J0D01*
G01X1860131Y267559D01*
X1860103Y267530D01*
X1860029Y267500D01*
X1842700D01*
G03X1841286Y266914I0J-1999D01*
G01X1837086Y262714D01*
G03X1836500Y261300I1413J-1414D01*
G01Y164011D01*
G02X1836441Y163869I-200J0D01*
G01X1812231Y139659D01*
X1812203Y139630D01*
X1812129Y139600D01*
X1783162D01*
G03X1781748Y139014I0J-1999D01*
G01X1775321Y132588D01*
X1775192Y132568D01*
X1775133Y132599D01*
G03X1773504Y133002I-1631J-3099D01*
G01X1773500D01*
G03X1769998Y129500I0J-3502D01*
G01Y129496D01*
G03X1770401Y127867I3502J2D01*
G01X1770432Y127808D01*
X1770412Y127679D01*
X1765512Y122779D01*
X1765397Y122754D01*
X1765341Y122775D01*
G03X1765157Y122839I-1242J-3275D01*
G01X1765118Y122852D01*
X1765057Y122904D01*
X1764913Y123195D01*
G02X1764895Y123317I179J89D01*
G01X1764901Y123354D01*
X1764906Y123370D01*
G03X1765102Y124523I-3306J1155D01*
G01Y124524D01*
G03X1758098I-3502J0D01*
G03X1760543Y121185I3502J0D01*
G01X1760582Y121172D01*
X1760643Y121120D01*
X1760787Y120829D01*
G02X1760805Y120707I-179J-89D01*
G01X1760799Y120670D01*
X1760794Y120654D01*
G03X1760598Y119501I3306J-1155D01*
G01Y119498D01*
G03X1760825Y118258I3502J0D01*
G01X1760846Y118203D01*
X1760823Y118091D01*
X1760782Y118048D01*
G02X1760779Y118045I-143J140D01*
G01X1760734Y118000D01*
G02X1760732Y117998I-142J140D01*
G01X1760679Y117946D01*
G02X1760539Y117889I-140J143D01*
G01X1760483D01*
X1760459Y117895D01*
G03X1759601Y118002I-859J-3395D01*
G01X1759600D01*
G03X1756098Y114500I0J-3502D01*
G01Y114499D01*
G03X1756211Y113618I3502J1D01*
G01X1756225Y113566D01*
X1756197Y113464D01*
X1712757Y70023D01*
X1712729Y69994D01*
X1712655Y69964D01*
X1686164D01*
G03X1684750Y69378I0J-1999D01*
G01X1662659Y47287D01*
G03X1662073Y45873I1413J-1414D01*
G01Y8236D01*
G02X1662057Y8157I-200J-1D01*
G01X1662011Y8052D01*
X1661983Y8024D01*
G03X1661952Y7993I2106J-2137D01*
G01X1658017Y4059D01*
X1657989Y4030D01*
X1657915Y4000D01*
X1651898D01*
X1651795Y4074D01*
X1651774Y4135D01*
G03X1645146I-3314J-1132D01*
G01X1645125Y4074D01*
X1645022Y4000D01*
X1631898D01*
X1631795Y4074D01*
X1631774Y4135D01*
G03X1625146I-3314J-1132D01*
G01X1625125Y4074D01*
X1625022Y4000D01*
X1611898D01*
X1611795Y4074D01*
X1611774Y4135D01*
G03X1605146I-3314J-1132D01*
G01X1605125Y4074D01*
X1605022Y4000D01*
X1591898D01*
X1591795Y4074D01*
X1591774Y4135D01*
G03X1585146I-3314J-1132D01*
G01X1585125Y4074D01*
X1585022Y4000D01*
X1571898D01*
X1571795Y4074D01*
X1571774Y4135D01*
G03X1565146I-3314J-1132D01*
G01X1565125Y4074D01*
X1565022Y4000D01*
X1551898D01*
X1551795Y4074D01*
X1551774Y4135D01*
G03X1545146I-3314J-1132D01*
G01X1545125Y4074D01*
X1545022Y4000D01*
X1531898D01*
X1531795Y4074D01*
X1531774Y4135D01*
G03X1525146I-3314J-1132D01*
G01X1525125Y4074D01*
X1525022Y4000D01*
X1511898D01*
X1511795Y4074D01*
X1511774Y4135D01*
G03X1505146I-3314J-1132D01*
G01X1505125Y4074D01*
X1505022Y4000D01*
X1496657D01*
G02X1496489Y4092I0J200D01*
G01X1496462Y4134D01*
X1496454Y4236D01*
X1496498Y4332D01*
X1496523Y4365D01*
X1496539Y4379D01*
G03X1499168Y10197I-5123J5818D01*
G03X1491417Y17948I-7751J0D01*
G03X1485242Y14883I0J-7753D01*
G01X1485210Y14840D01*
X1485114Y14799D01*
X1484665Y14851D01*
X1484581Y14912D01*
X1484559Y14962D01*
G03X1480257Y17790I-4362J-1949D01*
G01X1480217D01*
X1480146Y17820D01*
X1480095Y17871D01*
G02Y18153I142J141D01*
G01X1480146Y18204D01*
X1480217Y18234D01*
X1480257D01*
G03X1475418Y23071I-60J4779D01*
G01Y23031D01*
X1475388Y22960D01*
X1475218Y22790D01*
X1475176D01*
X1475006Y22960D01*
X1474976Y23031D01*
Y23071D01*
G03X1465418I-4779J-59D01*
G01Y23031D01*
X1465388Y22960D01*
X1465248Y22820D01*
X1465177Y22790D01*
X1465137D01*
G03Y13234I60J-4778D01*
G01X1465177D01*
X1465248Y13204D01*
X1465299Y13153D01*
G02Y12871I-142J-141D01*
G01X1465248Y12820D01*
X1465177Y12790D01*
X1465137D01*
G03X1460418Y8012I60J-4779D01*
G03X1461773Y4679I4779J1D01*
G01X1461815Y4636D01*
X1461837Y4518D01*
X1461671Y4123D01*
G02X1461586Y4026I-185J76D01*
G01X1461539Y4000D01*
X306106D01*
G02X305938Y4092I0J200D01*
G01X305911Y4134D01*
X305903Y4236D01*
X305947Y4332D01*
X305972Y4365D01*
X305988Y4379D01*
G03X308617Y10197I-5123J5818D01*
G03X300866Y17948I-7751J0D01*
G03X294691Y14883I0J-7753D01*
G01X294659Y14840D01*
X294563Y14799D01*
X294114Y14851D01*
X294030Y14912D01*
X294008Y14962D01*
G03X289706Y17790I-4362J-1949D01*
G01X289666D01*
X289595Y17820D01*
X289424Y17991D01*
Y18033D01*
X289595Y18204D01*
X289666Y18234D01*
X289706D01*
G03X294424Y23012I-60J4778D01*
G03X289646Y27790I-4778J0D01*
G03X284868Y23072I0J-4778D01*
G01Y23032D01*
X284838Y22961D01*
X284667Y22790D01*
X284625D01*
X284454Y22961D01*
X284424Y23032D01*
Y23072D01*
G03X274868I-4778J-60D01*
G01Y23032D01*
X274838Y22961D01*
X274697Y22820D01*
X274626Y22790D01*
X274586D01*
G03Y13234I60J-4778D01*
G01X274626D01*
X274697Y13204D01*
X274868Y13033D01*
Y12991D01*
X274697Y12820D01*
X274626Y12790D01*
X274586D01*
G03X269868Y8012I60J-4778D01*
G03X271222Y4679I4779J0D01*
G01X271264Y4636D01*
X271286Y4518D01*
X271120Y4123D01*
G02X271035Y4026I-185J76D01*
G01X270988Y4000D01*
X236497D01*
G02X236355Y4059I0J200D01*
G01X233620Y6794D01*
X233591Y6822D01*
X233561Y6896D01*
Y11942D01*
G02X233875Y12106I200J0D01*
G02X233940Y12031I-114J-165D01*
G03X240866Y7760I6926J3480D01*
G03X248618Y15512I0J7752D01*
G03X248580Y16283I-7752J4D01*
G01X248576Y16314D01*
X248583Y16346D01*
G02X248822Y16498I195J-43D01*
G01X248862Y16489D01*
X248881Y16480D01*
G03X250866Y16048I1986J4347D01*
G03X246162Y21662I0J4778D01*
G01X246156Y21628D01*
X246121Y21568D01*
X245989Y21456D01*
X245845Y21455D01*
X245789Y21501D01*
G03X240866Y23264I-4923J-5992D01*
G03X233940Y18993I0J-7751D01*
G02X233875Y18918I-179J90D01*
G02X233561Y19082I-114J164D01*
G01Y71799D01*
G02X233604Y71923I200J0D01*
G01X233626Y71951D01*
X233682Y71986D01*
X233715Y71994D01*
G03X240851Y81000I-2115J9006D01*
G03X237128Y88418I-9252J0D01*
G01X237108Y88432D01*
X237080Y88467D01*
X237055Y88515D01*
G02X237144Y88784I179J90D01*
G01X237190Y88807D01*
X237242Y88805D01*
G03X237391Y88802I145J3500D01*
G03X240894Y92305I0J3503D01*
G03X240513Y93893I-3503J-1D01*
G01X240493Y93932D01*
X240490Y94004D01*
X240502Y94056D01*
X240516Y94081D01*
G03X240956Y95780I-3063J1700D01*
G03X240420Y97641I-3503J-1D01*
G01X240406Y97663D01*
X240391Y97709D01*
X240388Y97763D01*
X240399Y97818D01*
X240413Y97843D01*
G03X240832Y99503I-3084J1661D01*
G03X240303Y101352I-3503J-2D01*
G01X240288Y101376D01*
X240273Y101430D01*
Y101486D01*
X240288Y101540D01*
X240303Y101564D01*
G03X240832Y103412I-2973J1851D01*
G03X237331Y106914I-3502J0D01*
G01X237329D01*
G03X235437Y106359I0J-3502D01*
G02X235331Y106327I-109J168D01*
G02X235221Y106359I-1J200D01*
G03X233738Y106891I-1894J-2946D01*
G01X233737D01*
G02X233561Y107090I24J199D01*
G01Y129365D01*
G03X233560Y129447I-3000J4D01*
G01X233559Y129488D01*
X233574Y129526D01*
G02X233619Y129595I186J-72D01*
G01X233965Y129941D01*
G02X233967Y129943I142J-140D01*
G02X234107Y130000I140J-143D01*
G01X288489D01*
G02X288629Y129943I0J-200D01*
G01X288630Y129942D01*
X376005Y42566D01*
G02X376029Y42538I-139J-144D01*
G01Y42537D01*
G02X376043Y42335I-165J-113D01*
G01X375845Y41938D01*
X375732Y41878D01*
X375668Y41887D01*
G03X375192Y41920I-480J-3470D01*
G03X373773Y41619I2J-3503D01*
G01X373734Y41602D01*
X373650D01*
X373611Y41619D01*
G03X372192Y41920I-1421J-3202D01*
G03X370773Y41619I2J-3503D01*
G01X370734Y41602D01*
X370650D01*
X370611Y41619D01*
G03X369192Y41920I-1421J-3202D01*
G03Y34914I0J-3503D01*
G03X370611Y35215I-2J3503D01*
G01X370650Y35232D01*
X370734D01*
X370773Y35215D01*
G03X372192Y34914I1421J3202D01*
G03X373611Y35215I-2J3503D01*
G01X373650Y35232D01*
X373734D01*
X373773Y35215D01*
G03X375192Y34914I1421J3202D01*
G03X376611Y35215I-2J3503D01*
G01X376650Y35232D01*
X376734D01*
X376773Y35215D01*
G03X378192Y34914I1421J3202D01*
G03X381215Y36648I0J3502D01*
G01X381239Y36689D01*
X381315Y36739D01*
X381676Y36785D01*
G02X381843Y36728I26J-198D01*
G01X385553Y33019D01*
G03X386967Y32433I1414J1413D01*
G01X859631D01*
G02X859651Y32432I0J-200D01*
G02X859804Y32333I-20J-199D01*
G02X859813Y32317I-169J-106D01*
G01X859990Y31933D01*
X859974Y31818D01*
X859936Y31773D01*
G03X859098Y29500I2664J-2273D01*
G03X862600Y25998I3502J0D01*
G01X862602D01*
G03X863849Y26228I-1J3502D01*
G01X863891Y26244D01*
X863978Y26238D01*
X864099Y26171D01*
X864134Y26137D01*
X864147Y26116D01*
G03X867100Y24498I2953J1886D01*
G03X870158Y26292I0J3503D01*
G01X870178Y26327D01*
X870242Y26377D01*
X870452Y26432D01*
G02X870503Y26439I52J-193D01*
G01X870687D01*
X870737Y26425D01*
X870761Y26411D01*
G03X872533Y25930I1771J3020D01*
G03X876036Y29432I0J3503D01*
G03X875168Y31739I-3503J-1D01*
G01X875144Y31766D01*
X875114Y31845D01*
G02X875118Y31997I187J71D01*
G01X875260Y32314D01*
G02X875334Y32401I183J-81D01*
G01X875384Y32433D01*
X1004689D01*
G02X1004808Y32394I0J-200D01*
G03X1007192I1192J1607D01*
G02X1007311Y32433I119J-161D01*
G01X1010689D01*
G02X1010808Y32394I0J-200D01*
G03X1012000Y32000I1192J1606D01*
G01X1272214D01*
G03X1273628Y32586I0J1999D01*
G01X1279414Y38372D01*
G03X1280000Y39786I-1413J1414D01*
G01Y59200D01*
G02X1280200Y59400I200J0D01*
G01X1393300D01*
G03X1394714Y59986I0J1999D01*
G01X1458669Y123941D01*
G02X1458671Y123943I142J-140D01*
G02X1458811Y124000I140J-143D01*
G01X1533702D01*
G03X1535116Y124586I0J1999D01*
G01X1584514Y173984D01*
G03X1585100Y175398I-1413J1414D01*
G01Y290589D01*
G02X1585157Y290729I200J0D01*
G01X1585158Y290730D01*
X1597869Y303441D01*
G02X1597871Y303443I142J-140D01*
G02X1598011Y303500I140J-143D01*
G37*
G36*
G01X471471Y95361D02*
G03X472057Y96775I-1413J1414D01*
G01Y116171D01*
G03X471471Y117585I-1999J0D01*
G01X469582Y119474D01*
G03X468168Y120060I-1414J-1413D01*
G01X442377D01*
G02X442235Y120119I0J200D01*
G01X440879Y121475D01*
G02X440820Y121617I141J142D01*
G01Y135286D01*
G02X440879Y135428I200J0D01*
G01X442233Y136782D01*
G02X442375Y136841I142J-141D01*
G01X467788D01*
G03X469202Y137427I0J1999D01*
G01X471973Y140198D01*
G03X472559Y141612I-1413J1414D01*
G01Y165794D01*
G03X471973Y167208I-1999J0D01*
G01X466557Y172624D01*
G03X465143Y173210I-1414J-1413D01*
G01X442502D01*
G02X442360Y173269I0J200D01*
G01X441005Y174624D01*
G02X440946Y174766I141J142D01*
G01Y177478D01*
G02X441005Y177620I200J0D01*
G01X441826Y178441D01*
G02X441968Y178500I142J-141D01*
G01X481400D01*
G02X481600Y178300I0J-200D01*
G01Y75926D01*
G02X481400Y75726I-200J0D01*
G01X442252D01*
G02X442110Y75785I0J200D01*
G01X441132Y76763D01*
G02X441073Y76905I141J142D01*
G01Y91455D01*
G02X441132Y91597I200J0D01*
G01X441858Y92323D01*
G02X442000Y92382I142J-141D01*
G01X467664D01*
G03X469078Y92968I0J1999D01*
G01X471471Y95361D01*
G37*
G36*
G01X470387Y227371D02*
G03X470973Y228785I-1413J1414D01*
G01Y246544D01*
G03X470387Y247958I-1999J0D01*
G01X466105Y252240D01*
G03X464691Y252826I-1414J-1413D01*
G01X442048D01*
G02X441906Y252885I0J200D01*
G01X440677Y254114D01*
G02X440618Y254256I141J142D01*
G01Y264399D01*
G02X440677Y264541I200J0D01*
G01X442536Y266400D01*
G02X442678Y266459I142J-141D01*
G01X464437D01*
G03X465851Y267045I0J1999D01*
G01X470764Y271958D01*
G03X471350Y273372I-1413J1414D01*
G01Y289995D01*
G03X470764Y291409I-1999J0D01*
G01X466859Y295314D01*
G03X465445Y295900I-1414J-1413D01*
G01X440663D01*
G02X440521Y295959I0J200D01*
G01X439730Y296750D01*
G02X439671Y296892I141J142D01*
G01Y313506D01*
G02X439730Y313648I200J0D01*
G01X449023Y322941D01*
G02X449165Y323000I142J-141D01*
G01X481400D01*
G02X481600Y322800I0J-200D01*
G01Y218926D01*
G02X481400Y218726I-200J0D01*
G01X442240D01*
G02X442098Y218785I0J200D01*
G01X440678Y220205D01*
G02X440619Y220347I141J142D01*
G01Y221829D01*
G02X440678Y221971I200J0D01*
G01X441655Y222948D01*
G02X441797Y223007I142J-141D01*
G01X465195D01*
G03X466609Y223593I0J1999D01*
G01X470387Y227371D01*
G37*
G36*
G01X1174276Y272366D02*
G03X1175488Y275016I-2291J2650D01*
G03X1168484I-3502J0D01*
G03X1169696Y272366I3503J0D01*
G02X1169765Y272215I-131J-151D01*
G01Y271910D01*
G02X1169747Y271828I-200J1D01*
G01X1169730Y271790D01*
X1169697Y271761D01*
X1169695Y271759D01*
X1169689Y271754D01*
G03X1168484Y269110I2298J-2644D01*
G03X1171401Y265656I3503J0D01*
G01X1171427Y265652D01*
X1171482Y265627D01*
G02X1171535Y265591I-84J-181D01*
G02X1171590Y265505I-135J-147D01*
G01X1171695Y265177D01*
G02X1171646Y264974I-190J-61D01*
G01X1166086Y259414D01*
G03X1165500Y258000I1413J-1414D01*
G01Y244810D01*
G02X1165485Y244735I-200J1D01*
G01X1165470Y244697D01*
X1165441Y244669D01*
X1154331Y233559D01*
G02X1154309Y233540I-141J141D01*
G02X1154189Y233500I-120J160D01*
G01X1111400D01*
G03X1109986Y232914I0J-1999D01*
G01X1080859Y203787D01*
G02X1080837Y203768I-141J141D01*
G02X1080717Y203728I-120J160D01*
G01X1049795D01*
G02X1049720Y203743I1J200D01*
G01X1049682Y203758D01*
X1049654Y203787D01*
X1044172Y209269D01*
G02X1044153Y209291I141J141D01*
G02X1044113Y209411I160J120D01*
G01Y269587D01*
Y269599D01*
X1044114Y269609D01*
G02X1044162Y269728I200J-11D01*
G01X1044183Y269752D01*
G03X1044199Y269774I-153J128D01*
G01X1044200Y269775D01*
G02X1044257Y269833I168J-108D01*
G02X1044284Y269848I110J-167D01*
G03X1046302Y273020I-1484J3172D01*
G03X1045857Y274727I-3502J-1D01*
G01Y274728D01*
X1045856Y274729D01*
G02X1045832Y274810I176J96D01*
G01X1045829Y274855D01*
X1045952Y275182D01*
G02X1046000Y275255I187J-71D01*
G01X1046030Y275284D01*
X1046072Y275299D01*
G03X1048402Y278600I-1173J3301D01*
G03X1044900Y282102I-3502J0D01*
G01X1044895D01*
G03X1044567Y282086I6J-3502D01*
G01X1044558Y282085D01*
X1044531D01*
G02X1044459Y282098I-1J200D01*
G01X1044424Y282112D01*
X1044398Y282136D01*
X1044179Y282334D01*
G02X1044113Y282482I134J148D01*
G01Y324920D01*
G02X1044114Y324939I200J-1D01*
G02X1044172Y325062I199J-19D01*
G01X1047323Y328213D01*
G02X1047446Y328271I142J-141D01*
G01X1047456Y328272D01*
X1099329D01*
G03X1100743Y328858I0J1999D01*
G01X1102411Y330526D01*
G03X1102997Y331940I-1413J1414D01*
G01Y345840D01*
G03X1102411Y347254I-1999J0D01*
G01X1099262Y350403D01*
G03X1097848Y350989I-1414J-1413D01*
G01X1038045D01*
G03X1036631Y350403I0J-1999D01*
G01X1024231Y338003D01*
G03X1023645Y336589I1413J-1414D01*
G01Y306122D01*
G02X1023606Y306004I-200J1D01*
G01X1023598Y305993D01*
X1023594Y305988D01*
G03X1022768Y303729I2676J-2259D01*
G03X1023594Y301470I3502J0D01*
G01X1023598Y301465D01*
X1023606Y301454D01*
G02X1023645Y301336I-161J-119D01*
G01Y216359D01*
G02X1023626Y216275I-200J1D01*
G01X1023574Y216163D01*
X1023542Y216136D01*
G03Y213864I983J-1136D01*
G01X1023574Y213837D01*
X1023626Y213725D01*
G02X1023645Y213641I-181J-85D01*
G01Y193555D01*
G02X1023630Y193480I-200J1D01*
G01X1023615Y193442D01*
X1023586Y193414D01*
X1018843Y188671D01*
G03X1018841Y188669I140J-142D01*
G01X1018821Y188648D01*
X1018769Y188620D01*
X1018709Y188608D01*
X1018652Y188613D01*
X1018624Y188625D01*
G02X1018500Y188808I76J185D01*
G01Y200374D01*
G03X1017914Y201788I-1999J0D01*
G01X1015268Y204434D01*
G03X1013854Y205020I-1414J-1413D01*
G01X973633D01*
G03X972219Y204434I0J-1999D01*
G01X970074Y202289D01*
G03X969488Y200875I1413J-1414D01*
G01Y183679D01*
G03X970074Y182265I1999J0D01*
G01X980996Y171343D01*
G03X980998Y171341I142J140D01*
G01X981019Y171321D01*
X981047Y171269D01*
X981059Y171209D01*
X981054Y171152D01*
X981042Y171124D01*
G02X980859Y171000I-185J76D01*
G01X976961D01*
G02X976886Y171015I1J200D01*
G01X976848Y171030D01*
X976820Y171059D01*
X957965Y189914D01*
G03X956551Y190500I-1414J-1413D01*
G01X906500D01*
G03X905086Y189914I0J-1999D01*
G01X901586Y186414D01*
G03X901000Y185000I1413J-1414D01*
G01Y119000D01*
G03X901586Y117586I1999J0D01*
G01X908586Y110586D01*
G03X910000Y110000I1414J1413D01*
G01X1095106D01*
G02X1095125Y109999I-1J-200D01*
G02X1095248Y109941I-19J-199D01*
G01X1098941Y106248D01*
G02X1098999Y106125I-141J-142D01*
G01X1099000Y106115D01*
Y63567D01*
G03X1099586Y62153I1999J0D01*
G01X1114153Y47586D01*
G03X1115567Y47000I1414J1413D01*
G01X1275500D01*
G03X1275581Y47002I-9J2000D01*
G01X1275622Y47004D01*
X1275661Y46989D01*
G02X1275727Y46947I-72J-186D01*
G01X1275938Y46747D01*
G02X1276000Y46603I-138J-145D01*
G01Y40696D01*
G02X1275985Y40621I-200J1D01*
G01X1275970Y40583D01*
X1275941Y40555D01*
X1271445Y36059D01*
G02X1271423Y36040I-141J141D01*
G02X1271303Y36000I-120J160D01*
G01X1018877D01*
G02X1018759Y36039I1J200D01*
G03X1017567Y36433I-1192J-1606D01*
G01X485800D01*
G02X485600Y36633I0J200D01*
G01Y46602D01*
G02X485659Y46744I200J0D01*
G01X485660Y46745D01*
X485871Y46947D01*
G02X486013Y47003I139J-144D01*
G01X486096Y47001D01*
X486097Y47000D01*
X618033D01*
G03X619447Y47586I0J1999D01*
G01X634014Y62153D01*
G03X634600Y63567I-1413J1414D01*
G01Y106106D01*
G02X634601Y106125I200J-1D01*
G02X634659Y106248I199J-19D01*
G01X638352Y109941D01*
G02X638475Y109999I142J-141D01*
G01X638485Y110000D01*
X823600D01*
G03X825014Y110586I0J1999D01*
G01X832014Y117586D01*
G03X832600Y119000I-1413J1414D01*
G01Y185000D01*
G03X832014Y186414I-1999J0D01*
G01X828514Y189914D01*
G03X827100Y190500I-1414J-1413D01*
G01X778729D01*
G03X777315Y189914I0J-1999D01*
G01X754142Y166741D01*
G02X754120Y166722I-141J141D01*
G02X754000Y166682I-120J160D01*
G01X748863D01*
G02X748685Y166819I12J200D01*
G01X748565Y167179D01*
G02X748555Y167239I190J62D01*
G01X748554Y167271D01*
X748564Y167301D01*
X748573Y167331D01*
X748609Y167382D01*
X748635Y167402D01*
G03X748847Y167586I-1201J1598D01*
G01X763526Y182265D01*
G03X764112Y183679I-1413J1414D01*
G01Y200875D01*
G03X763526Y202289I-1999J0D01*
G01X761381Y204434D01*
G03X759967Y205020I-1414J-1413D01*
G01X719746D01*
G03X718332Y204434I0J-1999D01*
G01X715686Y201788D01*
G03X715100Y200374I1413J-1414D01*
G01Y183500D01*
G03X715686Y182086I1999J0D01*
G01X730186Y167586D01*
G03X730375Y167420I1411J1416D01*
G01X730398Y167401D01*
X730437Y167346D01*
G02X730464Y167168I-163J-116D01*
G01X730348Y166819D01*
G02X730170Y166682I-190J63D01*
G01X685618D01*
G02X685543Y166697I1J200D01*
G01X685505Y166712D01*
X685477Y166741D01*
X679912Y172306D01*
G02X679893Y172328I141J141D01*
G02X679853Y172448I160J120D01*
G01Y198682D01*
G02X679854Y198701I200J-1D01*
G02X679912Y198824I199J-19D01*
G01X680231Y199143D01*
G02X680354Y199201I142J-141D01*
G01X680364Y199202D01*
X684962D01*
G03X686376Y199788I0J1999D01*
G01X695517Y208929D01*
G03X696103Y210343I-1413J1414D01*
G01Y215272D01*
G03X695517Y216686I-1999J0D01*
G01X692797Y219406D01*
G03X691383Y219992I-1414J-1413D01*
G01X633276D01*
G02X633201Y220007I1J200D01*
G01X633163Y220022D01*
X633135Y220051D01*
X602802Y250384D01*
G02X602783Y250406I141J141D01*
G02X602743Y250526I160J120D01*
G01Y304403D01*
G02X602757Y304476I200J0D01*
G01X602794Y304572D01*
X602816Y304598D01*
G03Y306552I-1141J977D01*
G01X602794Y306578D01*
X602757Y306674D01*
G02X602743Y306747I186J73D01*
G01Y313604D01*
G03X602157Y315018I-1999J0D01*
G01X597899Y319276D01*
G03X596485Y319862I-1414J-1413D01*
G01X589180D01*
G03X587766Y319276I0J-1999D01*
G01X585688Y317198D01*
G03X585102Y315784I1413J-1414D01*
G01Y297935D01*
G03X585688Y296521I1999J0D01*
G01X591319Y290890D01*
G02X591377Y290767I-141J-142D01*
G01X591378Y290757D01*
Y286732D01*
G02X591359Y286646I-200J-1D01*
G01X591340Y286607D01*
X591307Y286579D01*
G02X591305Y286577I-142J140D01*
G01X591071Y286382D01*
X591039Y286355D01*
X591001Y286344D01*
G02X590922Y286336I-59J191D01*
G01X590908Y286338D01*
X590900Y286339D01*
X590895Y286340D01*
G03X590298Y286392I-601J-3450D01*
G03X586796Y282890I0J-3502D01*
G03X588003Y280246I3501J1D01*
G01X588010Y280239D01*
X588026Y280225D01*
X588051Y280192D01*
X588060Y280173D01*
G02X588078Y280089I-182J-83D01*
G01Y279784D01*
G02X588060Y279702I-200J1D01*
G01X588043Y279664D01*
X588010Y279635D01*
X588003Y279628D01*
G03X586796Y276984I2294J-2645D01*
G03X590298Y273482I3502J0D01*
G03X590895Y273534I-4J3502D01*
G01X590900Y273535D01*
X590908Y273536D01*
X590922Y273538D01*
G02X591001Y273530I20J-199D01*
G01X591039Y273519D01*
X591071Y273492D01*
X591305Y273297D01*
G02X591307Y273295I-140J-142D01*
G02X591358Y273228I-130J-152D01*
G01X591359D01*
G02X591378Y273142I-181J-85D01*
G01Y270638D01*
G02X591363Y270563I-200J1D01*
G01X591348Y270525D01*
X591319Y270497D01*
X587900Y267078D01*
G02X587878Y267059I-141J141D01*
G02X587758Y267019I-120J160D01*
G01X579855D01*
G02X579749Y267050I1J200D01*
G01X579663Y267104D01*
G02X579625Y267135I106J169D01*
G01X579605Y267156D01*
X579593Y267181D01*
G03X573341I-3126J-1582D01*
G01X573329Y267156D01*
X573309Y267135D01*
G02X573271Y267104I-144J138D01*
G01X573185Y267050D01*
G02X573079Y267019I-107J169D01*
G01X566461D01*
G02X566265Y267180I0J200D01*
G03X565928Y268132I-3435J-680D01*
G01X565917Y268153D01*
X565905Y268198D01*
G02Y268298I194J50D01*
G01X565917Y268343D01*
X565928Y268364D01*
G03X566334Y270000I-3098J1637D01*
G01Y270002D01*
G03X565931Y271632I-3503J-1D01*
G01X565919Y271654D01*
X565908Y271699D01*
X565902Y271724D01*
Y271773D01*
X565920Y271842D01*
X565931Y271863D01*
G03X566336Y273498I-3102J1636D01*
G01Y273500D01*
G03X565921Y275154I-3506J-1D01*
G01X565909Y275176D01*
X565897Y275223D01*
Y275277D01*
X565909Y275324D01*
X565921Y275346D01*
G03X566336Y277000I-3091J1655D01*
G03X559324I-3506J0D01*
G03X559739Y275346I3506J1D01*
G01X559751Y275324D01*
X559763Y275277D01*
Y275223D01*
X559751Y275176D01*
X559739Y275154D01*
G03X559324Y273500I3091J-1655D01*
G01Y273498D01*
G03X559729Y271863I3507J1D01*
G01X559740Y271842D01*
X559758Y271773D01*
Y271724D01*
X559752Y271699D01*
X559741Y271654D01*
X559729Y271632D01*
G03X559326Y270002I3100J-1631D01*
G01Y270000D01*
G03X559732Y268364I3504J1D01*
G01X559743Y268343D01*
X559755Y268298D01*
G02Y268198I-194J-50D01*
G01X559743Y268153D01*
X559732Y268132D01*
G03X559395Y267180I3098J-1632D01*
G02X559325Y267063I-196J38D01*
G01X559299Y267042D01*
X559235Y267019D01*
X554818D01*
G02X554712Y267050I1J200D01*
G01X554626Y267104D01*
G02X554588Y267135I106J169D01*
G01X554568Y267156D01*
X554556Y267181D01*
G03X548304I-3126J-1582D01*
G01X548292Y267156D01*
X548272Y267135D01*
G02X548234Y267104I-144J138D01*
G01X548148Y267050D01*
G02X548042Y267019I-107J169D01*
G01X543649D01*
G02X543574Y267034I1J200D01*
G01X543536Y267049D01*
X543508Y267078D01*
X540904Y269682D01*
G02X540885Y269704I141J141D01*
G02X540845Y269824I160J120D01*
G01Y314530D01*
G03X540259Y315944I-1999J0D01*
G01X537789Y318414D01*
G03X536375Y319000I-1414J-1413D01*
G01X486100D01*
G03X486019Y318998I9J-2000D01*
G01X485978Y318996D01*
X485939Y319011D01*
G02X485873Y319053I72J186D01*
G01X485662Y319253D01*
G02X485600Y319397I138J145D01*
G01Y325000D01*
G03X483600Y327000I-2000J0D01*
G01X453804D01*
G02X453638Y327089I0J200D01*
G01X453453Y327368D01*
G02X453420Y327458I166J112D01*
G01X453415Y327508D01*
X453435Y327555D01*
Y327557D01*
G03X453596Y328340I-1839J786D01*
G01Y334836D01*
G02X453696Y335009I200J0D01*
G01X453988Y335177D01*
G02X454139Y335197I100J-173D01*
G01X454196Y335182D01*
X454218Y335170D01*
G03X455945Y334714I1728J3046D01*
G01X455947D01*
G03X457365Y335014I0J3502D01*
G01X457366D01*
X457404Y335022D01*
G02X457488I42J-195D01*
G01X457526Y335014D01*
X457527D01*
G03X458944Y334714I1418J3202D01*
G01X458946D01*
G03X462087Y336666I0J3503D01*
G01X462101Y336694D01*
X462122Y336716D01*
G02X462171Y336754I146J-137D01*
G02X462267Y336778I95J-176D01*
G01X462625D01*
G02X462722Y336753I0J-200D01*
G01X462749Y336738D01*
X462791Y336694D01*
X462805Y336666D01*
G03X465946Y334714I3141J1551D01*
G01X465948D01*
G03X467364Y335014I-2J3502D01*
G01X467366D01*
G02X467466Y335030I81J-183D01*
G01X467499Y335027D01*
G03X468946Y334713I1449J3188D01*
G03X470364Y335014I-3J3502D01*
G01X470403Y335031D01*
X470489D01*
X470528Y335014D01*
G03X471946Y334713I1421J3201D01*
G03X474850Y336258I0J3502D01*
G01X474863Y336277D01*
X474903Y336314D01*
G02X474998Y336362I134J-148D01*
G02X475038Y336366I40J-196D01*
G01X475363D01*
G02X475529Y336277I0J-200D01*
G03X478445Y334714I2916J1939D01*
G01X478447D01*
G03X479865Y335014I0J3502D01*
G01X479866D01*
X479904Y335022D01*
G02X479988I42J-195D01*
G01X480026Y335014D01*
X480027D01*
G03X481445Y334714I1418J3202D01*
G01X481447D01*
G03X482865Y335014I0J3502D01*
G01X482866D01*
X482904Y335022D01*
G02X482988I42J-195D01*
G01X483026Y335014D01*
X483027D01*
G03X484444Y334714I1418J3202D01*
G01X484446D01*
G03X487948Y338216I0J3502D01*
G01Y338218D01*
G03X487648Y339634I-3502J-2D01*
G01Y339636D01*
X487640Y339674D01*
G02Y339758I195J42D01*
G01X487648Y339796D01*
Y339798D01*
G03X487948Y341214I-3202J1418D01*
G01Y341216D01*
G03X484446Y344718I-3502J0D01*
G01X484444D01*
G03X483027Y344418I1J-3502D01*
G02X482865I-81J183D01*
G03X481447Y344718I-1418J-3202D01*
G01X481445D01*
G03X480027Y344418I0J-3502D01*
G01X480026D01*
X479988Y344410D01*
G02X479904I-42J195D01*
G01X479866Y344418D01*
X479865D01*
G03X478447Y344718I-1418J-3202D01*
G01X478445D01*
G03X475542Y343174I1J-3502D01*
G01X475529Y343155D01*
X475489Y343118D01*
G02X475394Y343070I-134J148D01*
G02X475354Y343066I-40J196D01*
G01X475029D01*
G02X474863Y343155I0J200D01*
G03X471947Y344718I-2916J-1939D01*
G01X471945D01*
G03X470527Y344418I0J-3502D01*
G02X470365I-81J183D01*
G03X468946Y344719I-1421J-3202D01*
G03X467528Y344418I3J-3502D01*
G01X467489Y344401D01*
X467403D01*
X467364Y344418D01*
G03X465946Y344719I-1421J-3201D01*
G03X462805Y342766I0J-3502D01*
G02X462626Y342654I-180J88D01*
G01X462267D01*
G02X462170Y342679I0J200D01*
G01X462143Y342694D01*
X462101Y342738D01*
X462087Y342766D01*
G03X458946Y344718I-3141J-1551D01*
G01X458944D01*
G03X457527Y344418I1J-3502D01*
G02X457365I-81J183D01*
G03X455947Y344718I-1418J-3202D01*
G01X455945D01*
G03X454218Y344262I1J-3502D01*
G01X454196Y344250D01*
X454139Y344235D01*
G02X453988Y344255I-51J193D01*
G01X453696Y344423D01*
G02X453596Y344596I100J173D01*
G01Y401312D01*
G02X453796Y401512I200J0D01*
G01X458472D01*
G02X458614Y401453I0J-200D01*
G03X460746I1066J1056D01*
G02X460888Y401512I142J-141D01*
G01X478472D01*
G02X478614Y401453I0J-200D01*
G03X480746I1066J1056D01*
G02X480888Y401512I142J-141D01*
G01X498472D01*
G02X498614Y401453I0J-200D01*
G03X500746I1066J1056D01*
G02X500888Y401512I142J-141D01*
G01X518472D01*
G02X518614Y401453I0J-200D01*
G03X520746I1066J1056D01*
G02X520888Y401512I142J-141D01*
G01X538472D01*
G02X538614Y401453I0J-200D01*
G03X540746I1066J1056D01*
G02X540888Y401512I142J-141D01*
G01X558472D01*
G02X558614Y401453I0J-200D01*
G03X560746I1066J1056D01*
G02X560888Y401512I142J-141D01*
G01X578472D01*
G02X578614Y401453I0J-200D01*
G03X580746I1066J1056D01*
G02X580888Y401512I142J-141D01*
G01X598472D01*
G02X598614Y401453I0J-200D01*
G03X600746I1066J1056D01*
G02X600888Y401512I142J-141D01*
G01X618472D01*
G02X618614Y401453I0J-200D01*
G03X620746I1066J1056D01*
G02X620888Y401512I142J-141D01*
G01X638472D01*
G02X638614Y401453I0J-200D01*
G03X640746I1066J1056D01*
G02X640888Y401512I142J-141D01*
G01X658472D01*
G02X658614Y401453I0J-200D01*
G03X660746I1066J1056D01*
G02X660888Y401512I142J-141D01*
G01X678472D01*
G02X678614Y401453I0J-200D01*
G03X680746I1066J1056D01*
G02X680888Y401512I142J-141D01*
G01X698472D01*
G02X698614Y401453I0J-200D01*
G03X700746I1066J1056D01*
G02X700888Y401512I142J-141D01*
G01X718472D01*
G02X718614Y401453I0J-200D01*
G03X720746I1066J1056D01*
G02X720888Y401512I142J-141D01*
G01X738472D01*
G02X738614Y401453I0J-200D01*
G03X740746I1066J1056D01*
G02X740888Y401512I142J-141D01*
G01X758472D01*
G02X758614Y401453I0J-200D01*
G03X760746I1066J1056D01*
G02X760888Y401512I142J-141D01*
G01X778472D01*
G02X778614Y401453I0J-200D01*
G03X780746I1066J1056D01*
G02X780888Y401512I142J-141D01*
G01X798472D01*
G02X798614Y401453I0J-200D01*
G03X800746I1066J1056D01*
G02X800888Y401512I142J-141D01*
G01X818472D01*
G02X818614Y401453I0J-200D01*
G03X820746I1066J1056D01*
G02X820888Y401512I142J-141D01*
G01X838472D01*
G02X838614Y401453I0J-200D01*
G03X840746I1066J1056D01*
G02X840888Y401512I142J-141D01*
G01X858472D01*
G02X858614Y401453I0J-200D01*
G03X860746I1066J1056D01*
G02X860888Y401512I142J-141D01*
G01X878472D01*
G02X878614Y401453I0J-200D01*
G03X880746I1066J1056D01*
G02X880888Y401512I142J-141D01*
G01X898472D01*
G02X898614Y401453I0J-200D01*
G03X900746I1066J1056D01*
G02X900888Y401512I142J-141D01*
G01X918472D01*
G02X918614Y401453I0J-200D01*
G03X920746I1066J1056D01*
G02X920888Y401512I142J-141D01*
G01X938472D01*
G02X938614Y401453I0J-200D01*
G03X940746I1066J1056D01*
G02X940888Y401512I142J-141D01*
G01X958472D01*
G02X958614Y401453I0J-200D01*
G03X960746I1066J1056D01*
G02X960888Y401512I142J-141D01*
G01X978472D01*
G02X978614Y401453I0J-200D01*
G03X980746I1066J1056D01*
G02X980888Y401512I142J-141D01*
G01X998472D01*
G02X998614Y401453I0J-200D01*
G03X1000746I1066J1056D01*
G02X1000888Y401512I142J-141D01*
G01X1018472D01*
G02X1018614Y401453I0J-200D01*
G03X1020746I1066J1056D01*
G02X1020888Y401512I142J-141D01*
G01X1038472D01*
G02X1038614Y401453I0J-200D01*
G03X1040746I1066J1056D01*
G02X1040888Y401512I142J-141D01*
G01X1058472D01*
G02X1058614Y401453I0J-200D01*
G03X1060746I1066J1056D01*
G02X1060888Y401512I142J-141D01*
G01X1078472D01*
G02X1078614Y401453I0J-200D01*
G03X1080746I1066J1056D01*
G02X1080888Y401512I142J-141D01*
G01X1098472D01*
G02X1098614Y401453I0J-200D01*
G03X1100746I1066J1056D01*
G02X1100888Y401512I142J-141D01*
G01X1118472D01*
G02X1118614Y401453I0J-200D01*
G03X1120746I1066J1056D01*
G02X1120888Y401512I142J-141D01*
G01X1138472D01*
G02X1138614Y401453I0J-200D01*
G03X1140746I1066J1056D01*
G02X1140888Y401512I142J-141D01*
G01X1158472D01*
G02X1158614Y401453I0J-200D01*
G03X1160746I1066J1056D01*
G02X1160888Y401512I142J-141D01*
G01X1178472D01*
G02X1178614Y401453I0J-200D01*
G03X1180746I1066J1056D01*
G02X1180888Y401512I142J-141D01*
G01X1198472D01*
G02X1198614Y401453I0J-200D01*
G03X1200746I1066J1056D01*
G02X1200888Y401512I142J-141D01*
G01X1218472D01*
G02X1218614Y401453I0J-200D01*
G03X1220746I1066J1056D01*
G02X1220888Y401512I142J-141D01*
G01X1238472D01*
G02X1238614Y401453I0J-200D01*
G03X1240746I1066J1056D01*
G02X1240888Y401512I142J-141D01*
G01X1258472D01*
G02X1258614Y401453I0J-200D01*
G03X1260746I1066J1056D01*
G02X1260888Y401512I142J-141D01*
G01X1278472D01*
G02X1278614Y401453I0J-200D01*
G03X1280746I1066J1056D01*
G02X1280888Y401512I142J-141D01*
G01X1293000D01*
G02X1293200Y401312I0J-200D01*
G01Y319200D01*
G02X1293000Y319000I-200J0D01*
G01X1225966D01*
G03X1224552Y318414I0J-1999D01*
G01X1221901Y315763D01*
G03X1221315Y314349I1413J-1414D01*
G01Y269642D01*
G02X1221300Y269567I-200J1D01*
G01X1221285Y269529D01*
X1221256Y269501D01*
X1218949Y267194D01*
G02X1218927Y267175I-141J141D01*
G02X1218807Y267135I-120J160D01*
G01X1213770D01*
G02X1213594Y267241I1J200D01*
G03X1207406I-3094J-1642D01*
G02X1207230Y267135I-177J94D01*
G01X1202707D01*
G02X1202582Y267179I0J200D01*
G02X1202512Y267289I125J157D01*
G01Y267290D01*
G03X1202198Y268132I-3411J-793D01*
G01X1202187Y268153D01*
X1202175Y268198D01*
G02Y268298I194J50D01*
G01X1202187Y268343D01*
X1202198Y268364D01*
G03X1202604Y270000I-3098J1637D01*
G01Y270002D01*
G03X1202201Y271632I-3503J-1D01*
G01X1202189Y271654D01*
X1202178Y271699D01*
X1202172Y271724D01*
Y271773D01*
X1202190Y271842D01*
X1202201Y271863D01*
G03X1202606Y273498I-3102J1636D01*
G01Y273500D01*
G03X1202191Y275154I-3506J-1D01*
G01X1202179Y275176D01*
X1202167Y275223D01*
Y275277D01*
X1202179Y275324D01*
X1202191Y275346D01*
G03X1202606Y277000I-3091J1655D01*
G03X1195594I-3506J0D01*
G03X1196009Y275346I3506J1D01*
G01X1196021Y275324D01*
X1196033Y275277D01*
Y275223D01*
X1196021Y275176D01*
X1196009Y275154D01*
G03X1195594Y273500I3091J-1655D01*
G01Y273498D01*
G03X1195999Y271863I3507J1D01*
G01X1196010Y271842D01*
X1196028Y271773D01*
Y271724D01*
X1196022Y271699D01*
X1196011Y271654D01*
X1195999Y271632D01*
G03X1195596Y270002I3100J-1631D01*
G01Y270000D01*
G03X1196002Y268364I3504J1D01*
G01X1196013Y268343D01*
X1196025Y268298D01*
G02Y268198I-194J-50D01*
G01X1196013Y268153D01*
X1196002Y268132D01*
G03X1195688Y267290I3097J-1635D01*
G01Y267289D01*
G02X1195618Y267179I-195J47D01*
G02X1195493Y267135I-125J156D01*
G01X1190970D01*
G02X1190794Y267241I1J200D01*
G03X1184606I-3094J-1642D01*
G02X1184430Y267135I-177J94D01*
G01X1175556D01*
G02X1175460Y267159I-1J200D01*
G01X1175439Y267171D01*
X1175403Y267204D01*
X1175389Y267226D01*
X1175207Y267504D01*
G02X1175180Y267565I167J110D01*
G02X1175191Y267695I194J49D01*
G01Y267696D01*
G03X1175488Y269105I-3206J1411D01*
G01Y269110D01*
G03X1174277Y271759I-3503J0D01*
G01X1174271Y271764D01*
X1174265Y271770D01*
G02X1174207Y271903I142J141D01*
G01Y272215D01*
G02X1174276Y272366I200J0D01*
G37*
G36*
G01X486511Y180500D02*
X555989D01*
G02X556131Y180441I0J-200D01*
G01X559541Y177031D01*
G02X559600Y176889I-141J-142D01*
G01Y164044D01*
G02X559495Y163867I-200J-1D01*
G03X557653Y160784I1659J-3083D01*
G03X557709Y160159I3502J-1D01*
G01X557718Y160110D01*
X557689Y160017D01*
X557131Y159459D01*
G02X556989Y159400I-142J141D01*
G01X547900D01*
G03X546486Y158814I0J-1999D01*
G01X542086Y154414D01*
G03X541500Y153000I1413J-1414D01*
G01Y133200D01*
G03X542086Y131786I1999J0D01*
G01X543266Y130606D01*
G03X544680Y130020I1414J1413D01*
G01X548775D01*
G02X548919Y129959I0J-200D01*
G03X553941I2511J2441D01*
G02X554085Y130020I144J-139D01*
G01X557169D01*
G02X557311Y129961I0J-200D01*
G01X559541Y127731D01*
G02X559600Y127589I-141J-142D01*
G01Y119287D01*
X559595Y119265D01*
G03X559505Y118477I3412J-789D01*
G03X559595Y117689I3502J1D01*
G01X559600Y117667D01*
Y114933D01*
X559595Y114911D01*
G03X559505Y114123I3412J-789D01*
G03X559595Y113335I3502J1D01*
G01X559600Y113313D01*
Y52911D01*
G02X559541Y52769I-200J0D01*
G01X557831Y51059D01*
G02X557689Y51000I-142J141D01*
G01X487011D01*
G02X486869Y51059I0J200D01*
G01X485659Y52269D01*
G02X485600Y52411I141J142D01*
G01Y179589D01*
G02X485659Y179731I200J0D01*
G01X486369Y180441D01*
G02X486511Y180500I142J-141D01*
G37*
G36*
G01X487011Y315000D02*
X535464D01*
G02X535606Y314941I0J-200D01*
G01X536786Y313761D01*
G02X536845Y313619I-141J-142D01*
G01Y268913D01*
G03X537431Y267499I1999J0D01*
G01X541325Y263605D01*
G03X542739Y263019I1414J1413D01*
G01X548986D01*
G02X549118Y262969I0J-200D01*
G03X551430Y262098I2311J2631D01*
G03X553742Y262969I1J3502D01*
G02X553874Y263019I132J-150D01*
G01X559400D01*
G02X559600Y262819I0J-200D01*
G01Y252487D01*
X559595Y252465D01*
G03X559505Y251677I3412J-789D01*
G03X559595Y250889I3502J1D01*
G01X559600Y250867D01*
Y248133D01*
X559595Y248111D01*
G03X559505Y247323I3412J-789D01*
G03X559595Y246535I3502J1D01*
G01X559600Y246513D01*
Y187911D01*
G02X559541Y187769I-200J0D01*
G01X556331Y184559D01*
G02X556189Y184500I-142J141D01*
G01X486511D01*
G02X486369Y184559I0J200D01*
G01X485659Y185269D01*
G02X485600Y185411I141J142D01*
G01Y313589D01*
G02X485659Y313731I200J0D01*
G01X486869Y314941D01*
G02X487011Y315000I142J-141D01*
G37*
G36*
G01X590091Y315862D02*
X595574D01*
G02X595716Y315803I0J-200D01*
G01X598684Y312835D01*
G02X598743Y312693I-141J-142D01*
G01Y249615D01*
G03X599329Y248201I1999J0D01*
G01X630952Y216578D01*
G03X632366Y215992I1414J1413D01*
G01X690472D01*
G02X690614Y215933I0J-200D01*
G01X692044Y214503D01*
G02X692103Y214361I-141J-142D01*
G01Y211254D01*
G02X692044Y211112I-200J0D01*
G01X684193Y203261D01*
G02X684051Y203202I-142J141D01*
G01X679462D01*
G03X678048Y202616I0J-1999D01*
G01X676439Y201007D01*
G03X675853Y199593I1413J-1414D01*
G01Y171537D01*
G03X676439Y170123I1999J0D01*
G01X683294Y163268D01*
G03X684708Y162682I1414J1413D01*
G01X754911D01*
G03X756325Y163268I0J1999D01*
G01X779498Y186441D01*
G02X779640Y186500I142J-141D01*
G01X826189D01*
G02X826331Y186441I0J-200D01*
G01X828541Y184231D01*
G02X828600Y184089I-141J-142D01*
G01Y119911D01*
G02X828541Y119769I-200J0D01*
G01X822831Y114059D01*
G02X822689Y114000I-142J141D01*
G01X637583D01*
G03X636169Y113414I0J-1999D01*
G01X631186Y108431D01*
G03X630600Y107017I1413J-1414D01*
G01Y64478D01*
G02X630541Y64336I-200J0D01*
G01X617264Y51059D01*
G02X617122Y51000I-142J141D01*
G01X565511D01*
G02X565369Y51059I0J200D01*
G01X563659Y52769D01*
G02X563600Y52911I141J142D01*
G01Y110578D01*
X563688Y110687D01*
X563757Y110702D01*
G03X566509Y114123I-750J3421D01*
G03X565839Y116182I-3502J-1D01*
G02Y116418I162J118D01*
G03X566509Y118477I-2832J2060D01*
G03X563757Y121898I-3502J0D01*
G01X563688Y121913D01*
X563600Y122022D01*
Y127789D01*
G02X563659Y127931I200J0D01*
G01X565689Y129961D01*
G02X565831Y130020I142J-141D01*
G01X571575D01*
G02X571719Y129959I0J-200D01*
G03X576741I2511J2441D01*
G02X576885Y130020I144J-139D01*
G01X580120D01*
G03X581534Y130606I0J1999D01*
G01X583514Y132586D01*
G03X584100Y134000I-1413J1414D01*
G01Y151100D01*
G03X583514Y152514I-1999J0D01*
G01X577214Y158814D01*
G03X575800Y159400I-1414J-1413D01*
G01X568081D01*
G02X567923Y159478I0J200D01*
G01X567700Y159765D01*
X567682Y159855D01*
X567694Y159901D01*
G03X567807Y160784I-3389J882D01*
G03X564305Y164286I-3502J0D01*
G03X564031Y164275I3J-3502D01*
G01X563989Y164272D01*
X563911Y164299D01*
X563664Y164527D01*
G02X563600Y164674I136J147D01*
G01Y243778D01*
X563688Y243887D01*
X563757Y243902D01*
G03X566509Y247323I-750J3421D01*
G03X565839Y249382I-3502J-1D01*
G02Y249618I162J118D01*
G03X566509Y251677I-2832J2060D01*
G03X563757Y255098I-3502J0D01*
G01X563688Y255113D01*
X563600Y255222D01*
Y262819D01*
G02X563800Y263019I200J0D01*
G01X574023D01*
G02X574155Y262969I0J-200D01*
G03X576467Y262098I2311J2631D01*
G03X578779Y262969I1J3502D01*
G02X578911Y263019I132J-150D01*
G01X588669D01*
G03X590083Y263605I0J1999D01*
G01X594792Y268314D01*
G03X595378Y269728I-1413J1414D01*
G01Y291659D01*
G03X594792Y293073I-1999J0D01*
G01X589161Y298704D01*
G02X589102Y298846I141J142D01*
G01Y314873D01*
G02X589161Y315015I200J0D01*
G01X589949Y315803D01*
G02X590091Y315862I142J-141D01*
G37*
G36*
G01X719159Y199605D02*
X720515Y200961D01*
G02X720657Y201020I142J-141D01*
G01X759056D01*
G02X759198Y200961I0J-200D01*
G01X760053Y200106D01*
G02X760112Y199964I-141J-142D01*
G01Y184590D01*
G02X760053Y184448I-200J0D01*
G01X746664Y171059D01*
G02X746522Y171000I-142J141D01*
G01X732511D01*
G02X732369Y171059I0J200D01*
G01X719159Y184269D01*
G02X719100Y184411I141J142D01*
G01Y199463D01*
G02X719159Y199605I200J0D01*
G37*
G36*
G01X1038956Y346989D02*
X1096937D01*
G02X1097079Y346930I0J-200D01*
G01X1098938Y345071D01*
G02X1098997Y344929I-141J-142D01*
G01Y332851D01*
G02X1098938Y332709I-200J0D01*
G01X1098560Y332331D01*
X1098532Y332302D01*
X1098458Y332272D01*
X1046554D01*
G03X1045140Y331686I0J-1999D01*
G01X1040699Y327245D01*
G03X1040113Y325831I1413J-1414D01*
G01Y275337D01*
G02X1040069Y275212I-200J0D01*
G03Y270828I2730J-2192D01*
G02X1040113Y270703I-156J-125D01*
G01Y208500D01*
G03X1040699Y207086I1999J0D01*
G01X1046327Y201458D01*
G02X1046379Y201268I-142J-141D01*
G01X1046295Y200935D01*
G02X1046161Y200793I-194J49D01*
G01X1046159Y200792D01*
G03X1043660Y197437I1003J-3355D01*
G03X1050666I3503J0D01*
G03X1050227Y199134I-3503J-1D01*
G01Y199135D01*
G02X1050229Y199333I175J97D01*
G01X1050404Y199629D01*
G02X1050416Y199648I175J-97D01*
G02X1050577Y199728I160J-120D01*
G01X1081628D01*
G03X1083042Y200314I0J1999D01*
G01X1112169Y229441D01*
G02X1112311Y229500I142J-141D01*
G01X1155100D01*
G03X1156514Y230086I0J1999D01*
G01X1168914Y242486D01*
G03X1169500Y243900I-1413J1414D01*
G01Y257089D01*
G02X1169559Y257231I200J0D01*
G01X1175404Y263076D01*
G02X1175546Y263135I142J-141D01*
G01X1185092D01*
G02X1185167Y263120I-1J-200D01*
G01X1185268Y263079D01*
X1185296Y263053D01*
G03X1190104I2404J2548D01*
G01X1190132Y263079D01*
X1190233Y263120D01*
G02X1190308Y263135I76J-185D01*
G01X1197800D01*
G02X1198000Y262935I0J-200D01*
G01Y255072D01*
G02X1197893Y254894I-200J-1D01*
G02X1197880Y254888I-90J179D01*
G03X1195775Y251677I1397J-3211D01*
G03X1196445Y249618I3502J1D01*
G02Y249382I-162J-118D01*
G03X1195775Y247323I2832J-2060D01*
G03X1197880Y244112I3502J0D01*
G02X1197893Y244106I-77J-185D01*
G02X1198000Y243928I-93J-177D01*
G01Y165611D01*
G02X1197941Y165469I-200J0D01*
G01X1195917Y163445D01*
X1195887Y163430D01*
G03X1194279Y161823I1537J-3146D01*
G01X1194265Y161793D01*
X1194031Y161559D01*
X1194003Y161530D01*
X1193929Y161500D01*
X1183800D01*
G03X1182386Y160914I0J-1999D01*
G01X1176414Y154942D01*
G03X1175828Y153528I1413J-1414D01*
G01Y132192D01*
G03X1176414Y130778I1999J0D01*
G01X1176795Y130397D01*
G03X1178209Y129811I1414J1413D01*
G01X1185266D01*
G02X1185397Y129762I0J-200D01*
G03X1190003I2303J2637D01*
G02X1190134Y129811I131J-151D01*
G01X1196878D01*
G02X1197020Y129752I0J-200D01*
G01X1197941Y128831D01*
G02X1198000Y128689I-141J-142D01*
G01Y121872D01*
G02X1197893Y121694I-200J-1D01*
G02X1197880Y121688I-90J179D01*
G03X1195775Y118477I1397J-3211D01*
G03X1196445Y116418I3502J1D01*
G02Y116182I-162J-118D01*
G03X1195775Y114123I2832J-2060D01*
G03X1197880Y110912I3502J0D01*
G02X1197893Y110906I-77J-185D01*
G02X1198000Y110728I-93J-177D01*
G01Y52911D01*
G02X1197941Y52769I-200J0D01*
G01X1196231Y51059D01*
X1196203Y51030D01*
X1196129Y51000D01*
X1116478D01*
G02X1116336Y51059I0J200D01*
G01X1103059Y64336D01*
X1103030Y64364D01*
X1103000Y64438D01*
Y107017D01*
G03X1102414Y108431I-1999J0D01*
G01X1097431Y113414D01*
G03X1096017Y114000I-1414J-1413D01*
G01X910911D01*
G02X910769Y114059I0J200D01*
G01X905059Y119769D01*
X905030Y119797D01*
X905000Y119871D01*
Y184089D01*
G02X905059Y184231I200J0D01*
G01X907269Y186441D01*
G02X907411Y186500I142J-141D01*
G01X955640D01*
G02X955782Y186441I0J-200D01*
G01X977794Y164429D01*
G03X979208Y163843I1414J1413D01*
G01X1006654D01*
G03X1008068Y164429I0J1999D01*
G01X1017914Y174275D01*
G03X1018500Y175689I-1413J1414D01*
G01Y182589D01*
G02X1018559Y182731I200J0D01*
G01X1020468Y184640D01*
G02X1020670Y184689I141J-142D01*
G01X1021063Y184563D01*
X1021136Y184479D01*
X1021145Y184423D01*
G03X1024600Y181498I3455J578D01*
G03X1028102Y185000I0J3502D01*
G03X1025177Y188455I-3503J0D01*
G01X1025121Y188464D01*
X1025037Y188537D01*
X1024911Y188930D01*
G02X1024960Y189132I191J61D01*
G01X1027059Y191231D01*
G03X1027645Y192645I-1413J1414D01*
G01Y204182D01*
G02X1027748Y204357I200J0D01*
G01X1028053Y204527D01*
G02X1028255Y204523I98J-175D01*
G01X1028256Y204522D01*
G03X1030098Y203998I1843J2978D01*
G01X1030100D01*
G03Y211002I0J3502D01*
G01X1030098D01*
G03X1028256Y210478I1J-3502D01*
G01X1028255Y210477D01*
G02X1028053Y210473I-104J171D01*
G01X1027748Y210643D01*
G02X1027645Y210818I97J175D01*
G01Y211221D01*
G02X1027701Y211360I200J0D01*
G01X1027807Y211471D01*
X1027875Y211503D01*
X1027912Y211505D01*
G03Y218495I-237J3495D01*
G01X1027875Y218497D01*
X1027807Y218529D01*
X1027701Y218640D01*
G02X1027645Y218779I144J139D01*
G01Y278179D01*
Y278190D01*
G02X1027722Y278337I200J-11D01*
G02X1027733Y278345I123J-158D01*
G01X1028049Y278558D01*
X1028148Y278569D01*
X1028194Y278550D01*
G03X1029498Y278298I1304J3250D01*
G01X1029501D01*
G03X1030919Y278598I0J3502D01*
G02X1031081I81J-183D01*
G03X1032498Y278298I1418J3202D01*
G01X1032500D01*
G03Y285302I0J3502D01*
G01X1032498D01*
G03X1031081Y285002I1J-3502D01*
G02X1030919I-81J183D01*
G03X1029501Y285302I-1418J-3202D01*
G01X1029498D01*
G03X1028194Y285050I0J-3502D01*
G01X1028148Y285031D01*
X1028049Y285042D01*
X1027733Y285255D01*
G02X1027722Y285263I112J166D01*
G02X1027645Y285410I123J158D01*
G01Y300378D01*
G02X1027760Y300559I200J0D01*
G03Y306899I-1491J3170D01*
G02X1027645Y307080I85J181D01*
G01Y335678D01*
G02X1027704Y335820I200J0D01*
G01X1038814Y346930D01*
G02X1038956Y346989I142J-141D01*
G37*
G36*
G01X973547Y200106D02*
X974402Y200961D01*
G02X974544Y201020I142J-141D01*
G01X1012943D01*
G02X1013085Y200961I0J-200D01*
G01X1014441Y199605D01*
G02X1014500Y199463I-141J-142D01*
G01Y184411D01*
G02X1014441Y184269I-200J0D01*
G01X1001231Y171059D01*
G02X1001089Y171000I-142J141D01*
G01X987078D01*
G02X986936Y171059I0J200D01*
G01X973547Y184448D01*
G02X973488Y184590I141J142D01*
G01Y199964D01*
G02X973547Y200106I200J0D01*
G37*
G36*
G01X1204711Y180500D02*
X1275800D01*
G02X1276000Y180300I0J-200D01*
G01Y52411D01*
G02X1275941Y52269I-200J0D01*
G01X1274731Y51059D01*
G02X1274589Y51000I-142J141D01*
G01X1203911D01*
G02X1203769Y51059I0J200D01*
G01X1202059Y52769D01*
G02X1202000Y52911I141J142D01*
G01Y111851D01*
G02X1202042Y111974I200J0D01*
G03X1202779Y114123I-2765J2149D01*
G03X1202109Y116182I-3502J-1D01*
G02Y116418I162J118D01*
G03X1202779Y118477I-2832J2060D01*
G03X1202042Y120626I-3502J0D01*
G02X1202000Y120749I158J123D01*
G01Y128789D01*
G02X1202059Y128931I200J0D01*
G01X1202880Y129752D01*
G02X1203022Y129811I142J-141D01*
G01X1208066D01*
G02X1208197Y129762I0J-200D01*
G03X1212803I2303J2637D01*
G02X1212934Y129811I131J-151D01*
G01X1219382D01*
G03X1220796Y130397I0J1999D01*
G01X1224817Y134418D01*
G03X1225403Y135832I-1413J1414D01*
G01Y153697D01*
G03X1224817Y155111I-1999J0D01*
G01X1219014Y160914D01*
G03X1217600Y161500I-1414J-1413D01*
G01X1204111D01*
G02X1203969Y161559I0J200D01*
G01X1203736Y161792D01*
X1203721Y161822D01*
G03X1202113Y163430I-3146J-1538D01*
G01X1202083Y163445D01*
X1202059Y163469D01*
G02X1202000Y163611I141J142D01*
G01Y177789D01*
G02X1202059Y177931I200J0D01*
G01X1204569Y180441D01*
G02X1204711Y180500I142J-141D01*
G37*
G36*
G01X1226877Y315000D02*
X1274589D01*
G02X1274731Y314941I0J-200D01*
G01X1275941Y313731D01*
G02X1276000Y313589I-141J-142D01*
G01Y185411D01*
G02X1275941Y185269I-200J0D01*
G01X1275231Y184559D01*
G02X1275089Y184500I-142J141D01*
G01X1202200D01*
G02X1202000Y184700I0J200D01*
G01Y245051D01*
G02X1202042Y245174I200J0D01*
G03X1202779Y247323I-2765J2149D01*
G03X1202109Y249382I-3502J-1D01*
G02Y249618I162J118D01*
G03X1202779Y251677I-2832J2060D01*
G03X1202042Y253826I-3502J0D01*
G02X1202000Y253949I158J123D01*
G01Y262935D01*
G02X1202200Y263135I200J0D01*
G01X1207930D01*
G02X1208069Y263079I0J-200D01*
G03X1212931I2431J2522D01*
G02X1213070Y263135I139J-144D01*
G01X1219718D01*
G03X1221132Y263721I0J1999D01*
G01X1224729Y267318D01*
G03X1225315Y268732I-1413J1414D01*
G01Y313438D01*
G02X1225374Y313580I200J0D01*
G01X1226735Y314941D01*
G02X1226877Y315000I142J-141D01*
G37*
G36*
G01X1296301Y143307D02*
G03X1295715Y141893I1413J-1414D01*
G01Y119370D01*
G03X1296301Y117956I1999J0D01*
G01X1298191Y116066D01*
G03X1299605Y115480I1414J1413D01*
G01X1322625D01*
G02X1322767Y115421I0J-200D01*
G01X1323366Y114822D01*
G02X1323425Y114680I-141J-142D01*
G01Y99121D01*
G02X1323366Y98979I-200J0D01*
G01X1322263Y97876D01*
G02X1322121Y97817I-142J141D01*
G01X1300614D01*
G03X1299200Y97231I0J-1999D01*
G01X1296303Y94334D01*
G03X1295717Y92920I1413J-1414D01*
G01Y74910D01*
G03X1296303Y73496I1999J0D01*
G01X1298570Y71229D01*
G03X1299984Y70643I1414J1413D01*
G01X1322751D01*
G02X1322893Y70584I0J-200D01*
G01X1323618Y69859D01*
G02X1323677Y69717I-141J-142D01*
G01Y63600D01*
G02X1323477Y63400I-200J0D01*
G01X1280200D01*
G02X1280000Y63600I0J200D01*
G01Y156968D01*
G02X1280200Y157168I200J0D01*
G01X1320581D01*
G02X1320723Y157109I0J-200D01*
G01X1320999Y156833D01*
G02X1321058Y156691I-141J-142D01*
G01Y155112D01*
G02X1320999Y154970I-200J0D01*
G01X1320400Y154371D01*
G02X1320258Y154312I-142J141D01*
G01X1308134D01*
G03X1306720Y153726I0J-1999D01*
G01X1296301Y143307D01*
G37*
G36*
G01X1426030Y660444D02*
G03Y653178I3105J-3633D01*
G02X1426100Y653026I-130J-152D01*
G01Y652722D01*
G02X1426030Y652570I-200J0D01*
G03X1424356Y648937I3105J-3633D01*
G03X1429134Y644158I4779J0D01*
G03X1432767Y645833I-1J4779D01*
G02X1432919Y645903I152J-130D01*
G01X1433223D01*
G02X1433375Y645833I0J-200D01*
G03X1437008Y644158I3634J3104D01*
G03X1441786Y648935I0J4778D01*
G01Y648937D01*
G03X1440112Y652570I-4779J0D01*
G02X1440042Y652722I130J152D01*
G01Y653026D01*
G02X1440112Y653178I200J0D01*
G03X1441324Y654759I-3103J3634D01*
G02X1441447Y654865I181J-86D01*
G01X1441729Y654950D01*
G02X1441889Y654931I58J-191D01*
G03X1447875I2993J5030D01*
G02X1448035Y654950I102J-172D01*
G01X1448317Y654865D01*
G02X1448440Y654759I-58J-192D01*
G03X1449652Y653178I4315J2053D01*
G02X1449722Y653026I-130J-152D01*
G01Y652722D01*
G02X1449652Y652570I-200J0D01*
G03X1447978Y648937I3105J-3633D01*
G03X1452756Y644158I4779J0D01*
G03X1456389Y645833I-1J4779D01*
G02X1456541Y645903I152J-130D01*
G01X1456845D01*
G02X1456997Y645833I0J-200D01*
G03X1460630Y644158I3634J3104D01*
G03X1465408Y648935I0J4778D01*
G01Y648937D01*
G03X1463734Y652570I-4779J0D01*
G02X1463664Y652722I130J152D01*
G01Y653026D01*
G02X1463734Y653178I200J0D01*
G03Y660444I-3105J3633D01*
G02X1463664Y660596I130J152D01*
G01Y660900D01*
G02X1463734Y661052I200J0D01*
G03X1465408Y664685I-3105J3633D01*
G03X1460630Y669464I-4779J0D01*
G03X1456997Y667789I1J-4779D01*
G02X1456845Y667719I-152J130D01*
G01X1456541D01*
G02X1456389Y667789I0J200D01*
G03X1452756Y669464I-3634J-3104D01*
G03X1448047Y665498I0J-4779D01*
G02X1447941Y665353I-197J33D01*
G01X1447613Y665186D01*
X1447519D01*
X1447476Y665207D01*
G03X1442288I-2594J-5246D01*
G01X1442245Y665186D01*
X1442151D01*
X1441823Y665353D01*
G02X1441717Y665498I91J178D01*
G03X1437008Y669464I-4709J-813D01*
G03X1433375Y667789I1J-4779D01*
G02X1433223Y667719I-152J130D01*
G01X1432919D01*
G02X1432767Y667789I0J200D01*
G03X1431880Y668595I-3632J-3105D01*
G02X1431820Y668856I115J164D01*
G03X1432256Y670547I-3065J1692D01*
G03X1432240Y670879I-3502J-2D01*
G02X1432380Y671089I199J19D01*
G02X1437006Y671787I4627J-14987D01*
G01X1442324D01*
G02X1442513Y671651I0J-200D01*
G03X1449145I3316J1127D01*
G02X1449334Y671787I189J-64D01*
G01X1462324D01*
G02X1462513Y671651I0J-200D01*
G03X1469145I3316J1127D01*
G02X1469334Y671787I189J-64D01*
G01X1482324D01*
G02X1482513Y671651I0J-200D01*
G03X1483586Y670089I3315J1128D01*
G01X1483587Y670088D01*
G02X1483652Y669884I-129J-153D01*
G01X1483559Y669533D01*
G02X1483402Y669387I-193J51D01*
G01X1483401D01*
G03X1480619Y667789I851J-4702D01*
G02X1480467Y667719I-152J130D01*
G01X1480163D01*
G02X1480011Y667789I0J200D01*
G03X1476378Y669464I-3634J-3104D01*
G03X1471600Y664687I0J-4778D01*
G01Y664685D01*
G03X1473274Y661052I4779J0D01*
G02X1473344Y660900I-130J-152D01*
G01Y660596D01*
G02X1473274Y660444I-200J0D01*
G03Y653178I3105J-3633D01*
G02X1473344Y653026I-130J-152D01*
G01Y652722D01*
G02X1473274Y652570I-200J0D01*
G03X1471600Y648937I3105J-3633D01*
G03X1476378Y644158I4779J0D01*
G03X1480011Y645833I-1J4779D01*
G02X1480163Y645903I152J-130D01*
G01X1480467D01*
G02X1480619Y645833I0J-200D01*
G03X1484252Y644158I3634J3104D01*
G03X1489030Y648935I0J4778D01*
G01Y648937D01*
G03X1487356Y652570I-4779J0D01*
G02X1487286Y652722I130J152D01*
G01Y653026D01*
G02X1487356Y653178I200J0D01*
G03Y660444I-3105J3633D01*
G02X1487286Y660596I130J152D01*
G01Y660900D01*
G02X1487356Y661052I200J0D01*
G03X1489030Y664685I-3105J3633D01*
G01Y664686D01*
G03X1486806Y668724I-4778J0D01*
G02X1486714Y668919I106J169D01*
G01X1486760Y669278D01*
X1486897Y669443D01*
G03X1489145Y671651I-1068J3335D01*
G02X1489334Y671787I189J-64D01*
G01X1502324D01*
G02X1502513Y671651I0J-200D01*
G03X1505647Y669281I3316J1127D01*
G01X1505648D01*
G02X1505829Y669138I-11J-200D01*
G01X1505936Y668776D01*
G02X1505861Y668557I-192J-57D01*
G03X1503882Y664685I2800J-3873D01*
G03X1505557Y661052I4779J1D01*
G02X1505627Y660900I-130J-152D01*
G01Y660596D01*
G02X1505557Y660444I-200J0D01*
G03X1503882Y656811I3104J-3634D01*
G03X1505557Y653178I4779J1D01*
G02X1505627Y653026I-130J-152D01*
G01Y652722D01*
G02X1505557Y652570I-200J0D01*
G03X1503882Y648937I3104J-3634D01*
G03X1508661Y644158I4779J0D01*
G03X1512294Y645833I-1J4779D01*
G02X1512446Y645903I152J-130D01*
G01X1512750D01*
G02X1512902Y645833I0J-200D01*
G03X1516535Y644158I3634J3104D01*
G03X1521314Y648937I0J4779D01*
G03X1519639Y652570I-4779J-1D01*
G02X1519569Y652722I130J152D01*
G01Y653026D01*
G02X1519639Y653178I200J0D01*
G03X1521314Y656811I-3104J3634D01*
G03X1519639Y660444I-4779J-1D01*
G02X1519569Y660596I130J152D01*
G01Y660900D01*
G02X1519639Y661052I200J0D01*
G03X1521314Y664685I-3104J3634D01*
G03X1516535Y669464I-4779J0D01*
G03X1512902Y667789I1J-4779D01*
G02X1512750Y667719I-152J130D01*
G01X1512446D01*
G02X1512294Y667789I0J200D01*
G03X1508661Y669464I-3634J-3104D01*
G03X1508437Y669458I16J-4779D01*
G01X1508435D01*
G02X1508241Y669583I-9J200D01*
G01X1508099Y669932D01*
G02X1508152Y670157I185J75D01*
G03X1509145Y671651I-2323J2621D01*
G02X1509334Y671787I189J-64D01*
G01X1522324D01*
G02X1522513Y671651I0J-200D01*
G03X1529145I3316J1127D01*
G02X1529334Y671787I189J-64D01*
G01X1542324D01*
G02X1542513Y671651I0J-200D01*
G03X1549145I3316J1127D01*
G02X1549334Y671787I189J-64D01*
G01X1562324D01*
G02X1562513Y671651I0J-200D01*
G03X1569145I3316J1127D01*
G02X1569334Y671787I189J-64D01*
G01X1582324D01*
G02X1582513Y671651I0J-200D01*
G03X1584589Y669503I3316J1127D01*
G01X1584590D01*
G02X1584718Y669333I-71J-187D01*
G01X1584750Y668975D01*
G02X1584654Y668786I-199J-18D01*
G01X1584653Y668785D01*
G03X1582328Y664685I2454J-4101D01*
G03X1584003Y661052I4779J1D01*
G02X1584073Y660900I-130J-152D01*
G01Y660596D01*
G02X1584003Y660444I-200J0D01*
G03X1582328Y656811I3104J-3634D01*
G03X1584003Y653178I4779J1D01*
G02X1584073Y653026I-130J-152D01*
G01Y652722D01*
G02X1584003Y652570I-200J0D01*
G03X1582328Y648937I3104J-3634D01*
G03X1584003Y645304I4779J1D01*
G02X1584073Y645152I-130J-152D01*
G01Y644848D01*
G02X1584003Y644696I-200J0D01*
G03X1582328Y641063I3104J-3634D01*
G03X1584003Y637430I4779J1D01*
G02X1584073Y637278I-130J-152D01*
G01Y636974D01*
G02X1584003Y636822I-200J0D01*
G03X1582328Y633189I3104J-3634D01*
G03X1584003Y629556I4779J1D01*
G02X1584073Y629404I-130J-152D01*
G01Y629100D01*
G02X1584003Y628948I-200J0D01*
G03X1582328Y625315I3104J-3634D01*
G03X1584003Y621682I4779J1D01*
G02X1584073Y621530I-130J-152D01*
G01Y621226D01*
G02X1584003Y621074I-200J0D01*
G03X1582328Y617441I3104J-3634D01*
G03X1584003Y613808I4779J1D01*
G02X1584073Y613656I-130J-152D01*
G01Y613352D01*
G02X1584003Y613200I-200J0D01*
G03X1582328Y609567I3104J-3634D01*
G03X1584003Y605934I4779J1D01*
G02X1584073Y605782I-130J-152D01*
G01Y605478D01*
G02X1584003Y605326I-200J0D01*
G03X1582328Y601693I3104J-3634D01*
G03X1587107Y596914I4779J0D01*
G03X1590740Y598589I-1J4779D01*
G02X1590892Y598659I152J-130D01*
G01X1591196D01*
G02X1591348Y598589I0J-200D01*
G03X1594981Y596914I3634J3104D01*
G03X1599760Y601693I0J4779D01*
G03X1598085Y605326I-4779J-1D01*
G02X1598015Y605478I130J152D01*
G01Y605782D01*
G02X1598085Y605934I200J0D01*
G03X1599760Y609567I-3104J3634D01*
G03X1598085Y613200I-4779J-1D01*
G02X1598015Y613352I130J152D01*
G01Y613656D01*
G02X1598085Y613808I200J0D01*
G03X1599760Y617441I-3104J3634D01*
G03X1598085Y621074I-4779J-1D01*
G02X1598015Y621226I130J152D01*
G01Y621530D01*
G02X1598085Y621682I200J0D01*
G03X1599760Y625315I-3104J3634D01*
G03X1598085Y628948I-4779J-1D01*
G02X1598015Y629100I130J152D01*
G01Y629404D01*
G02X1598085Y629556I200J0D01*
G03X1599760Y633189I-3104J3634D01*
G03X1598085Y636822I-4779J-1D01*
G02X1598015Y636974I130J152D01*
G01Y637278D01*
G02X1598085Y637430I200J0D01*
G03X1599760Y641063I-3104J3634D01*
G03X1598085Y644696I-4779J-1D01*
G02X1598015Y644848I130J152D01*
G01Y645152D01*
G02X1598085Y645304I200J0D01*
G03X1599760Y648937I-3104J3634D01*
G03X1598085Y652570I-4779J-1D01*
G02X1598015Y652722I130J152D01*
G01Y653026D01*
G02X1598085Y653178I200J0D01*
G03X1599760Y656811I-3104J3634D01*
G03X1598085Y660444I-4779J-1D01*
G02X1598015Y660596I130J152D01*
G01Y660900D01*
G02X1598085Y661052I200J0D01*
G03X1599759Y664591I-3104J3634D01*
G01Y664592D01*
G02X1599875Y664768I200J-5D01*
G01X1600196Y664918D01*
G02X1600406Y664892I84J-182D01*
G03X1602598Y664122I2192J2736D01*
G01X1602599D01*
G03X1603732Y664311I-3J3506D01*
G01X1603797Y664322D01*
G02X1603968Y664225I0J-200D01*
G02X1606236Y656102I-13417J-8124D01*
G01Y653953D01*
G02X1606100Y653764I-200J0D01*
G03Y647132I1126J-3316D01*
G02X1606236Y646943I-64J-189D01*
G01Y642912D01*
G03X1610546Y629289I23685J0D01*
G01X1610582Y629174D01*
X1610552Y629068D01*
G03X1610025Y627220I2977J-1848D01*
G03X1613527Y623718I3502J0D01*
G03X1615243Y624168I-1J3501D01*
G02X1615464Y624152I98J-174D01*
G03X1615890Y623831I14466J18754D01*
G03X1625069Y619730I14031J19082D01*
G01X1625224Y619574D01*
G03X1628658Y616759I3434J687D01*
G03X1631960Y619095I0J3502D01*
G02X1632148Y619228I188J-67D01*
G01X1643098D01*
G02X1643240Y619169I0J-200D01*
G01X1645945Y616464D01*
G02X1646004Y616322I-141J-142D01*
G01Y307700D01*
G02X1645804Y307500I-200J0D01*
G01X1597100D01*
G03X1595686Y306914I0J-1999D01*
G01X1581686Y292914D01*
G03X1581100Y291500I1413J-1414D01*
G01Y176309D01*
G02X1581041Y176167I-200J0D01*
G01X1532933Y128059D01*
G02X1532791Y128000I-142J141D01*
G01X1457900D01*
G03X1456486Y127414I0J-1999D01*
G01X1392531Y63459D01*
G02X1392389Y63400I-142J141D01*
G01X1327877D01*
G02X1327677Y63600I0J200D01*
G01Y70628D01*
G03X1327091Y72042I-1999J0D01*
G01X1325076Y74057D01*
G03X1323662Y74643I-1414J-1413D01*
G01X1300895D01*
G02X1300753Y74702I0J200D01*
G01X1299776Y75679D01*
G02X1299717Y75821I141J142D01*
G01Y92009D01*
G02X1299776Y92151I200J0D01*
G01X1301383Y93758D01*
G02X1301525Y93817I142J-141D01*
G01X1323032D01*
G03X1324446Y94403I0J1999D01*
G01X1326839Y96796D01*
G03X1327425Y98210I-1413J1414D01*
G01Y115591D01*
G03X1326839Y117005I-1999J0D01*
G01X1324950Y118894D01*
G03X1323536Y119480I-1414J-1413D01*
G01X1300516D01*
G02X1300374Y119539I0J200D01*
G01X1299774Y120139D01*
G02X1299715Y120281I141J142D01*
G01Y140982D01*
G02X1299774Y141124I200J0D01*
G01X1308903Y150253D01*
G02X1309045Y150312I142J-141D01*
G01X1320418D01*
G02X1320617Y150133I0J-200D01*
G03X1324100Y146998I3483J367D01*
G03X1327602Y150500I0J3502D01*
G03X1325188Y153829I-3502J0D01*
G01X1325050Y154019D01*
X1325051Y154036D01*
G03X1325058Y154201I-1993J167D01*
G01Y157602D01*
G03X1324472Y159016I-1999J0D01*
G01X1322906Y160582D01*
G03X1321492Y161168I-1414J-1413D01*
G01X1280200D01*
G02X1280000Y161368I0J200D01*
G01Y191608D01*
G02X1280200Y191808I200J0D01*
G01X1319905D01*
G03X1321319Y192394I0J1999D01*
G01X1321345Y192420D01*
G02X1321627I141J-142D01*
G03X1324100Y191398I2473J2481D01*
G03X1327602Y194900I0J3502D01*
G03X1325489Y198116I-3504J0D01*
G01X1325368Y198299D01*
Y202435D01*
G03X1324782Y203849I-1999J0D01*
G01X1321574Y207057D01*
G03X1320160Y207643I-1414J-1413D01*
G01X1300387D01*
G02X1300245Y207702I0J200D01*
G01X1300217Y207730D01*
Y228410D01*
G02X1300276Y228552I200J0D01*
G01X1300875Y229151D01*
G02X1301017Y229210I142J-141D01*
G01X1323154D01*
G03X1324568Y229796I0J1999D01*
G01X1326710Y231938D01*
G03X1327296Y233352I-1413J1414D01*
G01Y245317D01*
G03X1326710Y246731I-1999J0D01*
G01X1323562Y249879D01*
G03X1322148Y250465I-1414J-1413D01*
G01X1302907D01*
G02X1302765Y250524I0J200D01*
G01X1299395Y253894D01*
G02X1299336Y254036I141J142D01*
G01Y271232D01*
G02X1299395Y271374I200J0D01*
G01X1300624Y272603D01*
G02X1300766Y272662I142J-141D01*
G01X1323533D01*
G03X1324947Y273248I0J1999D01*
G01X1327340Y275641D01*
G03X1327926Y277055I-1413J1414D01*
G01Y293994D01*
G03X1327340Y295408I-1999J0D01*
G01X1325262Y297486D01*
G03X1323848Y298072I-1414J-1413D01*
G01X1300073D01*
G02X1299931Y298131I0J200D01*
G01X1299709Y298353D01*
G02X1299650Y298495I141J142D01*
G01Y313599D01*
G03X1299064Y315013I-1999J0D01*
G01X1297259Y316818D01*
G02X1297200Y316960I141J142D01*
G01Y399209D01*
G02X1297303Y399384I200J0D01*
G01X1297610Y399553D01*
G02X1297706Y399578I97J-175D01*
G01X1297813Y399547D01*
G03X1299680Y399008I1867J2964D01*
G03X1302994Y401377I0J3502D01*
G01X1303015Y401438D01*
X1303118Y401512D01*
X1316242D01*
X1316345Y401438D01*
X1316366Y401377D01*
G03X1322994I3314J1133D01*
G01X1323015Y401438D01*
X1323118Y401512D01*
X1336242D01*
X1336345Y401438D01*
X1336366Y401377D01*
G03X1342994I3314J1133D01*
G01X1343015Y401438D01*
X1343118Y401512D01*
X1354331D01*
G03X1356257Y401568I-11J33527D01*
G02X1356450Y401453I12J-200D01*
G03X1359620Y399438I3170J1486D01*
G03X1363100Y402548I0J3502D01*
G02X1363246Y402718I199J-23D01*
G03X1387611Y430979I-8916J32320D01*
G01X1387760Y431148D01*
G03X1390384Y434539I-879J3391D01*
G03X1387994Y437860I-3502J0D01*
G01X1387933Y437881D01*
X1387858Y437985D01*
Y451029D01*
G02X1387994Y451218I200J0D01*
G03Y457860I-1112J3321D01*
G01X1387933Y457881D01*
X1387858Y457985D01*
Y471029D01*
G02X1387994Y471218I200J0D01*
G03Y477860I-1112J3321D01*
G01X1387933Y477881D01*
X1387858Y477985D01*
Y491029D01*
G02X1387994Y491218I200J0D01*
G03Y497860I-1112J3321D01*
G01X1387933Y497881D01*
X1387858Y497985D01*
Y511029D01*
G02X1387994Y511218I200J0D01*
G03Y517860I-1112J3321D01*
G01X1387933Y517881D01*
X1387858Y517985D01*
Y531029D01*
G02X1387994Y531218I200J0D01*
G03Y537860I-1112J3321D01*
G01X1387933Y537881D01*
X1387858Y537985D01*
Y551029D01*
G02X1387994Y551218I200J0D01*
G03Y557860I-1112J3321D01*
G01X1387933Y557881D01*
X1387858Y557985D01*
Y571029D01*
G02X1387994Y571218I200J0D01*
G03Y577860I-1112J3321D01*
G01X1387933Y577881D01*
X1387858Y577985D01*
Y591029D01*
G02X1387994Y591218I200J0D01*
G03Y597860I-1112J3321D01*
G01X1387933Y597881D01*
X1387858Y597985D01*
Y603543D01*
G02X1388889Y609136I15685J0D01*
G02X1389107Y609262I187J-72D01*
G03X1389639Y609221I534J3461D01*
G01X1389643D01*
G03X1393145Y612723I0J3502D01*
G03X1392615Y614575I-3502J0D01*
G01X1392585Y614681D01*
G02X1392646Y614825I200J0D01*
G02X1399664Y618741I10897J-11282D01*
G02X1399893Y618635I49J-194D01*
G03X1403035Y616679I3142J1546D01*
G03X1406373Y619123I0J3502D01*
G02X1406551Y619263I191J-60D01*
G03X1414255Y621865I-1037J15777D01*
G03X1416285Y623466I-8743J13174D01*
G03X1419408Y627496I-10773J11573D01*
G03X1419766Y628197I-13898J7539D01*
G03X1419776Y628218I-14270J6808D01*
G03X1420993Y631826I-14264J6821D01*
G02X1421143Y631980I196J-41D01*
G03X1423837Y635388I-809J3408D01*
G03X1421459Y638705I-3502J0D01*
G02X1421323Y638894I64J189D01*
G01Y651882D01*
G02X1421459Y652071I200J0D01*
G03X1423837Y655388I-1124J3317D01*
G03X1421684Y658620I-3502J0D01*
G01X1421561Y658805D01*
G02X1421564Y658840I200J0D01*
G02X1421625Y659168I15450J-2704D01*
G02X1423647Y664318I15382J-3067D01*
G02X1423861Y664408I170J-105D01*
G01X1424230Y664325D01*
X1424385Y664152D01*
G03X1426030Y661052I4749J533D01*
G02X1426100Y660900I-130J-152D01*
G01Y660596D01*
G02X1426030Y660444I-200J0D01*
G37*
G36*
G01X1293480Y314941D02*
X1295591Y312830D01*
G02X1295650Y312688I-141J-142D01*
G01Y297584D01*
G03X1296236Y296170I1999J0D01*
G01X1297748Y294658D01*
G03X1299162Y294072I1414J1413D01*
G01X1322937D01*
G02X1323079Y294013I0J-200D01*
G01X1323867Y293225D01*
G02X1323926Y293083I-141J-142D01*
G01Y277966D01*
G02X1323867Y277824I-200J0D01*
G01X1322764Y276721D01*
G02X1322622Y276662I-142J141D01*
G01X1299855D01*
G03X1298441Y276076I0J-1999D01*
G01X1295922Y273557D01*
G03X1295336Y272143I1413J-1414D01*
G01Y253125D01*
G03X1295922Y251711I1999J0D01*
G01X1300582Y247051D01*
G03X1301996Y246465I1414J1413D01*
G01X1321237D01*
G02X1321379Y246406I0J-200D01*
G01X1323237Y244548D01*
G02X1323296Y244406I-141J-142D01*
G01Y234263D01*
G02X1323237Y234121I-200J0D01*
G01X1322385Y233269D01*
G02X1322243Y233210I-142J141D01*
G01X1300106D01*
G03X1298692Y232624I0J-1999D01*
G01X1296803Y230735D01*
G03X1296217Y229321I1413J-1414D01*
G01Y206902D01*
G03X1296803Y205488I1999J0D01*
G01X1298062Y204229D01*
G03X1299476Y203643I1414J1413D01*
G01X1319249D01*
G02X1319391Y203584I0J-200D01*
G01X1321309Y201666D01*
G02X1321368Y201524I-141J-142D01*
G01Y198182D01*
G02X1321309Y198040I-200J0D01*
G01X1319136Y195867D01*
G02X1318994Y195808I-142J141D01*
G01X1280200D01*
G02X1280000Y196008I0J200D01*
G01Y314500D01*
G03X1279998Y314583I-2000J-7D01*
G01X1279996Y314624D01*
X1280025Y314700D01*
X1280253Y314938D01*
G02X1280398Y315000I145J-138D01*
G01X1293338D01*
G02X1293480Y314941I0J-200D01*
G37*
G36*
G01X1856652Y514607D02*
G02X1870016Y499095I-2321J-15513D01*
G01Y498327D01*
G02X1869956Y498184I-200J0D01*
G03Y496040I1052J-1072D01*
G02X1870016Y495897I-140J-143D01*
G01Y478327D01*
G02X1869956Y478184I-200J0D01*
G03Y476040I1052J-1072D01*
G02X1870016Y475897I-140J-143D01*
G01Y458327D01*
G02X1869956Y458184I-200J0D01*
G03Y456040I1052J-1072D01*
G02X1870016Y455897I-140J-143D01*
G01Y438327D01*
G02X1869956Y438184I-200J0D01*
G03Y436040I1052J-1072D01*
G02X1870016Y435897I-140J-143D01*
G01Y418327D01*
G02X1869956Y418184I-200J0D01*
G03Y416040I1052J-1072D01*
G02X1870016Y415897I-140J-143D01*
G01Y398327D01*
G02X1869956Y398184I-200J0D01*
G03Y396040I1052J-1072D01*
G02X1870016Y395897I-140J-143D01*
G01Y378327D01*
G02X1869956Y378184I-200J0D01*
G03Y376040I1052J-1072D01*
G02X1870016Y375897I-140J-143D01*
G01Y358327D01*
G02X1869956Y358184I-200J0D01*
G03Y356040I1052J-1072D01*
G02X1870016Y355897I-140J-143D01*
G01Y338327D01*
G02X1869956Y338184I-200J0D01*
G03Y336040I1052J-1072D01*
G02X1870016Y335897I-140J-143D01*
G01Y318327D01*
G02X1869956Y318184I-200J0D01*
G03Y316040I1052J-1072D01*
G02X1870016Y315897I-140J-143D01*
G01Y298327D01*
G02X1869956Y298184I-200J0D01*
G03Y296040I1052J-1072D01*
G02X1870016Y295897I-140J-143D01*
G01Y278327D01*
G02X1869956Y278184I-200J0D01*
G03Y276040I1052J-1072D01*
G02X1870016Y275897I-140J-143D01*
G01Y258327D01*
G02X1869956Y258184I-200J0D01*
G03Y256040I1052J-1072D01*
G02X1870016Y255897I-140J-143D01*
G01Y238327D01*
G02X1869956Y238184I-200J0D01*
G03Y236040I1052J-1072D01*
G02X1870016Y235897I-140J-143D01*
G01Y218327D01*
G02X1869956Y218184I-200J0D01*
G03Y216040I1052J-1072D01*
G02X1870016Y215897I-140J-143D01*
G01Y198327D01*
G02X1869956Y198184I-200J0D01*
G03Y196040I1052J-1072D01*
G02X1870016Y195897I-140J-143D01*
G01Y178327D01*
G02X1869956Y178184I-200J0D01*
G03Y176040I1052J-1072D01*
G02X1870016Y175897I-140J-143D01*
G01Y158327D01*
G02X1869956Y158184I-200J0D01*
G03Y156040I1052J-1072D01*
G02X1870016Y155897I-140J-143D01*
G01Y138327D01*
G02X1869956Y138184I-200J0D01*
G03Y136040I1052J-1072D01*
G02X1870016Y135897I-140J-143D01*
G01Y118327D01*
G02X1869956Y118184I-200J0D01*
G03Y116040I1052J-1072D01*
G02X1870016Y115897I-140J-143D01*
G01Y95127D01*
G02X1869956Y94984I-200J0D01*
G03Y92842I1053J-1071D01*
G02X1870016Y92699I-140J-143D01*
G01Y85709D01*
G02X1854853Y70033I-15685J0D01*
G02X1854704Y70092I-7J200D01*
G03X1853635Y70539I-1069J-1055D01*
G03X1852559Y70085I0J-1502D01*
G02X1852415Y70024I-144J139D01*
G01X1834855D01*
G02X1834711Y70085I0J200D01*
G03X1832559I-1076J-1048D01*
G02X1832415Y70024I-144J139D01*
G01X1814855D01*
G02X1814711Y70085I0J200D01*
G03X1812559I-1076J-1048D01*
G02X1812415Y70024I-144J139D01*
G01X1794855D01*
G02X1794711Y70085I0J200D01*
G03X1792559I-1076J-1048D01*
G02X1792415Y70024I-144J139D01*
G01X1774855D01*
G02X1774711Y70085I0J200D01*
G03X1772559I-1076J-1048D01*
G02X1772415Y70024I-144J139D01*
G01X1754855D01*
G02X1754711Y70085I0J200D01*
G03X1752559I-1076J-1048D01*
G02X1752415Y70024I-144J139D01*
G01X1751968D01*
G03X1732632Y60018I0J-23686D01*
G02X1732506Y59937I-163J115D01*
G03X1731284Y58461I280J-1476D01*
G03X1731333Y58080I1502J0D01*
G02X1731314Y57931I-193J-51D01*
G03X1728284Y46580I20654J-11593D01*
G02X1728222Y46437I-200J2D01*
G03X1727753Y45347I1032J-1090D01*
G03X1728221Y44258I1501J0D01*
G02X1728283Y44113I-138J-145D01*
G01Y26581D01*
G02X1728221Y26436I-200J0D01*
G03Y24258I1033J-1089D01*
G02X1728283Y24113I-138J-145D01*
G01Y19685D01*
G02X1712598Y4000I-15685J0D01*
G01X1709670D01*
G02X1709528Y4059I0J200D01*
G03X1707392I-1068J-1056D01*
G02X1707250Y4000I-142J141D01*
G01X1670271D01*
G02X1670129Y4059I0J200D01*
G01X1666194Y7993D01*
G03X1666135Y8051I-2132J-2110D01*
G02X1666073Y8195I138J145D01*
G01Y44962D01*
G02X1666132Y45104I200J0D01*
G01X1686933Y65905D01*
G02X1687075Y65964I142J-141D01*
G01X1713526D01*
G03X1714940Y66550I0J1999D01*
G01X1759361Y110971D01*
X1759438Y111001D01*
X1759479Y111000D01*
G03X1759600Y110998I118J3500D01*
G03X1763102Y114500I0J3502D01*
G03X1763100Y114621I-3502J3D01*
G01X1763099Y114662D01*
X1763129Y114739D01*
X1764375Y115984D01*
X1764437Y116014D01*
X1764471Y116017D01*
G03X1767583Y119129I-371J3483D01*
G01X1767586Y119163D01*
X1767616Y119225D01*
X1774530Y126140D01*
X1774570Y126165D01*
X1774593Y126172D01*
G03X1776828Y128407I-1093J3328D01*
G01X1776835Y128430D01*
X1776860Y128470D01*
X1783931Y135541D01*
G02X1784073Y135600I142J-141D01*
G01X1813000D01*
G03X1814414Y136186I0J1999D01*
G01X1839914Y161686D01*
G03X1840500Y163100I-1413J1414D01*
G01Y260389D01*
G02X1840559Y260531I200J0D01*
G01X1843469Y263441D01*
G02X1843611Y263500I142J-141D01*
G01X1860900D01*
G03X1862314Y264086I0J1999D01*
G01X1864814Y266586D01*
G03X1865400Y268000I-1413J1414D01*
G01Y303000D01*
G03X1864814Y304414I-1999J0D01*
G01X1862314Y306914D01*
G03X1860900Y307500I-1414J-1413D01*
G01X1650204D01*
G02X1650004Y307700I0J200D01*
G01Y616322D01*
G02X1650063Y616464I200J0D01*
G01X1652768Y619169D01*
G02X1652910Y619228I142J-141D01*
G01X1667466D01*
G02X1667608Y619169I0J-200D01*
G03X1669742I1067J1057D01*
G02X1669884Y619228I142J-141D01*
G01X1687449D01*
G02X1687595Y619165I0J-200D01*
G03X1689789I1097J1026D01*
G02X1689935Y619228I146J-137D01*
G01X1707449D01*
G02X1707595Y619165I0J-200D01*
G03X1709789I1097J1026D01*
G02X1709935Y619228I146J-137D01*
G01X1712598D01*
G02X1728277Y603966I0J-15685D01*
G02X1728218Y603818I-200J-6D01*
G03X1727773Y602751I1057J-1067D01*
G03X1728223Y601679I1502J0D01*
G02X1728283Y601536I-140J-143D01*
G01Y583966D01*
G02X1728223Y583823I-200J0D01*
G03Y581679I1052J-1072D01*
G02X1728283Y581536I-140J-143D01*
G01Y563966D01*
G02X1728223Y563823I-200J0D01*
G03Y561679I1052J-1072D01*
G02X1728283Y561536I-140J-143D01*
G01Y543966D01*
G02X1728223Y543823I-200J0D01*
G03Y541679I1052J-1072D01*
G02X1728283Y541536I-140J-143D01*
G01Y538465D01*
G03X1751968Y514780I23686J0D01*
G01X1754214D01*
G02X1754360Y514717I0J-200D01*
G03X1756548I1094J1029D01*
G02X1756694Y514780I146J-137D01*
G01X1774214D01*
G02X1774360Y514717I0J-200D01*
G03X1776548I1094J1029D01*
G02X1776694Y514780I146J-137D01*
G01X1814214D01*
G02X1814360Y514717I0J-200D01*
G03X1816548I1094J1029D01*
G02X1816694Y514780I146J-137D01*
G01X1834214D01*
G02X1834360Y514717I0J-200D01*
G03X1836548I1094J1029D01*
G02X1836694Y514780I146J-137D01*
G01X1854225D01*
G02X1854376Y514711I0J-200D01*
G03X1855509Y514195I1133J986D01*
G03X1856491Y514561I-1J1502D01*
G02X1856652Y514607I130J-152D01*
G37*
%LPD*%
G75*
G36*
G01X1744422Y204000D02*
G02X1747925Y207502I3503J-1D01*
G02X1751276Y205019I0J-3503D01*
G03X1751439Y204879I191J58D01*
G01X1751856Y204820D01*
X1751961Y204868D01*
X1751993Y204917D01*
G02X1754923Y206502I2931J-1918D01*
G01X1754925D01*
G02Y199498I0J-3502D01*
G01X1754921D01*
G02X1754357Y199544I2J3502D01*
G03X1754174Y199478I-32J-197D01*
G01X1753950Y199222D01*
G03X1753910Y199032I151J-131D01*
G01Y199031D01*
G02X1754066Y198000I-3347J-1034D01*
G02X1747060I-3503J0D01*
G02X1747638Y199927I3503J0D01*
G03X1747654Y200118I-167J110D01*
G01X1747498Y200472D01*
X1747418Y200534D01*
X1747368Y200542D01*
G02X1744422Y204000I556J3458D01*
G37*
G36*
G01X1741952Y190104D02*
G02X1738740Y187998I-3212J1396D01*
G02Y195002I0J3502D01*
G02X1742044Y192663I0J-3503D01*
G03X1742788Y192636I377J133D01*
G02X1746000Y194742I3212J-1396D01*
G02Y187738I0J-3502D01*
G02X1742696Y190077I0J3503D01*
G03X1741952Y190104I-377J-133D01*
G37*
G36*
G01X1619241Y157954D02*
G02X1622100Y159434I2859J-2021D01*
G02X1624344Y158620I-1J-3503D01*
G03X1624605Y158624I128J153D01*
G02X1626924Y159502I2319J-2624D01*
G01X1626925D01*
G02Y152498I0J-3502D01*
G02X1624681Y153311I0J3503D01*
G03X1624420Y153307I-128J-153D01*
G02X1622100Y152428I-2321J2624D01*
G02X1621172Y152553I-1J3503D01*
G03X1620956Y152476I-53J-193D01*
G02X1620550Y152000I-2856J2025D01*
G01X1620521Y151972D01*
X1620489Y151897D01*
X1620490Y151571D01*
G03X1620550Y151428I200J0D01*
G02X1621602Y148991I-2450J-2503D01*
G01X1621603Y148933D01*
X1621666Y148837D01*
X1622046Y148662D01*
G03X1622258Y148691I83J182D01*
G02X1624498Y149502I2241J-2691D01*
G01X1624500D01*
G02X1628002Y146000I0J-3502D01*
G01Y145998D01*
G02X1627587Y144344I-3502J0D01*
G03Y144156I176J-94D01*
G02X1628002Y142502I-3087J-1654D01*
G01Y142500D01*
G02X1620998I-3502J0D01*
G01Y142502D01*
G02X1621413Y144155I3502J-1D01*
G03Y144345I-176J95D01*
G02X1620998Y145934I3087J1655D01*
G01X1620997Y145992D01*
X1620934Y146088D01*
X1620554Y146263D01*
G03X1620342Y146234I-83J-182D01*
G02X1618100Y145422I-2243J2691D01*
G02X1614598Y148925I1J3503D01*
G01Y148926D01*
G02X1615650Y151428I3502J0D01*
G03X1615710Y151571I-140J143D01*
G01X1615711Y151857D01*
G03X1615651Y152000I-200J0D01*
G02X1614600Y154500I2448J2500D01*
G02X1618100Y158000I3500J0D01*
G01X1618102D01*
G02X1619025Y157876I0J-3500D01*
G03X1619241Y157954I52J193D01*
G37*
G36*
G01X1716791Y142684D02*
G02X1714100Y141422I-2692J2240D01*
G02Y148428I0J3503D01*
G02X1717601Y145012I0J-3502D01*
G03X1718309Y144766I400J10D01*
G02X1721000Y146028I2692J-2240D01*
G02Y139022I0J-3503D01*
G02X1717499Y142438I0J3502D01*
G03X1716791Y142684I-400J-10D01*
G37*
G36*
G01X1653828Y115388D02*
G02X1653548Y116759I3222J1372D01*
G01Y116760D01*
G02X1657050Y120262I3502J0D01*
G01X1657053D01*
G02X1658564Y119919I-1J-3502D01*
G03X1658736I86J180D01*
G02X1660247Y120262I1512J-3159D01*
G01X1660250D01*
G02X1663752Y116760I0J-3502D01*
G01Y116759D01*
G02X1663472Y115388I-3502J1D01*
G03Y115232I184J-78D01*
G02X1663752Y113861I-3222J-1372D01*
G01Y113860D01*
G02X1660250Y110358I-3502J0D01*
G01X1660247D01*
G02X1658736Y110701I1J3502D01*
G03X1658564I-86J-180D01*
G02X1657053Y110358I-1512J3159D01*
G01X1657050D01*
G02X1654130Y111926I0J3503D01*
G01X1654094Y111980D01*
X1653975Y112026D01*
X1653545Y111911D01*
G03X1653397Y111732I52J-193D01*
G01Y111731D01*
G02X1650002Y108548I-3395J219D01*
G01X1649999D01*
G02X1648328Y108987I1J3403D01*
G03X1648132I-98J-174D01*
G02X1646458Y108548I-1672J2964D01*
G02X1644784Y108987I-2J3403D01*
G03X1644588I-98J-174D01*
G02X1642915Y108548I-1672J2963D01*
G02X1641242Y108987I-1J3402D01*
G03X1641046I-98J-174D01*
G02X1639375Y108548I-1672J2964D01*
G01X1639372D01*
G02X1635970Y111950I0J3402D01*
G01Y111955D01*
G02X1636181Y113131I3402J-4D01*
G03Y113269I-188J69D01*
G02X1635970Y114445I3191J1180D01*
G01Y114450D01*
G02X1639372Y117852I3402J0D01*
G01X1639375D01*
G02X1641046Y117413I-1J-3403D01*
G03X1641242I98J174D01*
G02X1642915Y117852I1672J-2963D01*
G02X1644588Y117413I1J-3402D01*
G03X1644784I98J174D01*
G02X1646458Y117852I1672J-2964D01*
G02X1648132Y117413I2J-3403D01*
G03X1648328I98J174D01*
G02X1649999Y117852I1672J-2964D01*
G01X1650002D01*
G02X1653354Y115035I0J-3403D01*
G03X1653357Y115022I196J38D01*
G03X1653731Y114982I194J48D01*
G03X1653740Y115004I-180J87D01*
G02X1653828Y115232I3309J-1146D01*
G03Y115388I-184J78D01*
G37*
G36*
G01X1748098Y255500D02*
G02X1748303Y256683I3502J2D01*
G03Y256817I-188J67D01*
G02X1748098Y257997I3297J1181D01*
G01Y258000D01*
G02X1755102I3502J0D01*
G01Y257997D01*
G02X1754897Y256817I-3502J1D01*
G03Y256683I188J-67D01*
G02X1755102Y255500I-3297J-1181D01*
G02X1754897Y254317I-3502J-2D01*
G03Y254183I188J-67D01*
G02X1755102Y253000I-3297J-1181D01*
G02X1754897Y251817I-3502J-2D01*
G03Y251683I188J-67D01*
G02X1755102Y250500I-3297J-1181D01*
G02X1754897Y249317I-3502J-2D01*
G03Y249183I188J-67D01*
G02X1755102Y248003I-3297J-1181D01*
G01Y248000D01*
G02X1748098I-3502J0D01*
G01Y248003D01*
G02X1748303Y249183I3502J-1D01*
G03Y249317I-188J67D01*
G02X1748098Y250500I3297J1181D01*
G02X1748303Y251683I3502J2D01*
G03Y251817I-188J67D01*
G02X1748098Y253000I3297J1181D01*
G02X1748303Y254183I3502J2D01*
G03Y254317I-188J67D01*
G02X1748098Y255500I3297J1181D01*
G37*
G36*
G01X1737098D02*
G02X1737303Y256683I3502J2D01*
G03Y256817I-188J67D01*
G02X1737098Y257997I3297J1181D01*
G01Y258000D01*
G02X1744102I3502J0D01*
G01Y257997D01*
G02X1743897Y256817I-3502J1D01*
G03Y256683I188J-67D01*
G02X1744102Y255500I-3297J-1181D01*
G02X1743897Y254317I-3502J-2D01*
G03Y254183I188J-67D01*
G02X1744102Y253000I-3297J-1181D01*
G02X1743897Y251817I-3502J-2D01*
G03Y251683I188J-67D01*
G02X1744102Y250500I-3297J-1181D01*
G02X1743897Y249317I-3502J-2D01*
G03Y249183I188J-67D01*
G02X1744102Y248003I-3297J-1181D01*
G01Y248000D01*
G02X1737098I-3502J0D01*
G01Y248003D01*
G02X1737303Y249183I3502J-1D01*
G03Y249317I-188J67D01*
G02X1737098Y250500I3297J1181D01*
G02X1737303Y251683I3502J2D01*
G03Y251817I-188J67D01*
G02X1737098Y253000I3297J1181D01*
G02X1737303Y254183I3502J2D01*
G03Y254317I-188J67D01*
G02X1737098Y255500I3297J1181D01*
G37*
G36*
G01X1780430Y247357D02*
G02X1780730Y248776I3502J1D01*
G03Y248938I-183J81D01*
G02X1780430Y250357I3202J1418D01*
G02X1783932Y253860I3502J1D01*
G02X1787433Y250467I0J-3503D01*
G01X1787434Y250415D01*
X1787486Y250327D01*
X1787866Y250103D01*
X1787968Y250099D01*
X1788014Y250123D01*
G02X1789597Y250502I1585J-3123D01*
G01X1789600D01*
G02X1793102Y247000I0J-3502D01*
G01Y246998D01*
G02X1792687Y245344I-3502J0D01*
G03Y245156I176J-94D01*
G02X1793102Y243502I-3087J-1654D01*
G01Y243500D01*
G02X1789600Y239998I-3502J0D01*
G01X1789596D01*
G02X1788023Y240372I2J3503D01*
G01X1787974Y240397D01*
X1787869Y240391D01*
X1787534Y240171D01*
G03X1787444Y239993I110J-167D01*
G02X1787450Y239798I-3497J-205D01*
G02X1780444I-3503J0D01*
G02X1780745Y241217I3503J-2D01*
G03Y241379I-183J81D01*
G02X1780444Y242798I3202J1421D01*
G02X1781180Y244946I3502J0D01*
G03X1781179Y245192I-158J122D01*
G02X1780430Y247357I2753J2165D01*
G37*
G36*
G01X1771930D02*
G02X1772230Y248776I3502J1D01*
G03Y248938I-183J81D01*
G02X1771930Y250355I3202J1418D01*
G01Y250357D01*
G02X1778934I3502J0D01*
G01Y250355D01*
G02X1778634Y248938I-3502J1D01*
G03Y248776I183J-81D01*
G02X1778934Y247357I-3202J-1418D01*
G02X1778199Y245209I-3502J-1D01*
G03X1778200Y244963I158J-122D01*
G02X1778950Y242798I-2753J-2166D01*
G02X1778649Y241379I-3503J2D01*
G03Y241217I183J-81D01*
G02X1778950Y239798I-3202J-1421D01*
G02X1771944I-3503J0D01*
G02X1772245Y241217I3503J-2D01*
G03Y241379I-183J81D01*
G02X1771944Y242798I3202J1421D01*
G02X1772680Y244946I3502J0D01*
G03X1772679Y245192I-158J122D01*
G02X1771930Y247357I2753J2165D01*
G37*
G36*
G01X1762930Y247301D02*
Y247303D01*
G02X1763230Y248720I3502J-1D01*
G03Y248882I-183J81D01*
G02X1762930Y250299I3202J1418D01*
G01Y250301D01*
G02X1769934I3502J0D01*
G01Y250299D01*
G02X1769634Y248882I-3502J1D01*
G03Y248720I183J-81D01*
G02X1769934Y247301I-3202J-1418D01*
G02X1769219Y245180I-3502J0D01*
G03X1769220Y244937I159J-121D01*
G02X1769950Y242798I-2772J-2140D01*
G02X1769649Y241379I-3503J2D01*
G03Y241217I183J-81D01*
G02X1769950Y239798I-3202J-1421D01*
G02X1762944I-3503J0D01*
G02X1763245Y241217I3503J-2D01*
G03Y241379I-183J81D01*
G02X1762944Y242798I3202J1421D01*
G02X1763660Y244919I3503J-1D01*
G03X1763659Y245162I-159J121D01*
G02X1762930Y247301I2774J2139D01*
G37*
G36*
G01X1748098Y238000D02*
G02X1748303Y239183I3502J2D01*
G03Y239317I-188J67D01*
G02X1748098Y240497I3297J1181D01*
G01Y240500D01*
G02X1755102I3502J0D01*
G01Y240497D01*
G02X1754897Y239317I-3502J1D01*
G03Y239183I188J-67D01*
G02X1755102Y238000I-3297J-1181D01*
G02X1754897Y236817I-3502J-2D01*
G03Y236683I188J-67D01*
G02X1755102Y235500I-3297J-1181D01*
G02X1754897Y234317I-3502J-2D01*
G03Y234183I188J-67D01*
G02X1755102Y233003I-3297J-1181D01*
G01Y233000D01*
G02X1748098I-3502J0D01*
G01Y233003D01*
G02X1748303Y234183I3502J-1D01*
G03Y234317I-188J67D01*
G02X1748098Y235500I3297J1181D01*
G02X1748303Y236683I3502J2D01*
G03Y236817I-188J67D01*
G02X1748098Y238000I3297J1181D01*
G37*
G36*
G01X1737098D02*
G02X1737303Y239183I3502J2D01*
G03Y239317I-188J67D01*
G02X1737098Y240497I3297J1181D01*
G01Y240500D01*
G02X1744102I3502J0D01*
G01Y240497D01*
G02X1743897Y239317I-3502J1D01*
G03Y239183I188J-67D01*
G02X1744102Y238000I-3297J-1181D01*
G02X1743897Y236817I-3502J-2D01*
G03Y236683I188J-67D01*
G02X1744102Y235500I-3297J-1181D01*
G02X1743897Y234317I-3502J-2D01*
G03Y234183I188J-67D01*
G02X1744102Y233003I-3297J-1181D01*
G01Y233000D01*
G02X1737098I-3502J0D01*
G01Y233003D01*
G02X1737303Y234183I3502J-1D01*
G03Y234317I-188J67D01*
G02X1737098Y235500I3297J1181D01*
G02X1737303Y236683I3502J2D01*
G03Y236817I-188J67D01*
G02X1737098Y238000I3297J1181D01*
G37*
G36*
G01X1657998Y199000D02*
G02X1660500Y202357I3503J0D01*
G02X1660498Y202499I3500J120D01*
G01Y202501D01*
G02X1664000Y206002I3502J-1D01*
G02X1667502Y202500I0J-3502D01*
G02X1667501Y202402I-3502J-13D01*
G01Y202401D01*
G03X1667552Y202263I200J-5D01*
G01X1667763Y202029D01*
X1667831Y201995D01*
X1667870Y201992D01*
G02X1671102Y198500I-270J-3492D01*
G02X1667600Y194998I-3502J0D01*
G01X1667599D01*
G02X1664685Y196558I0J3502D01*
G03X1664534Y196647I-167J-110D01*
G01X1664177Y196676D01*
X1664091Y196643D01*
X1664060Y196609D01*
G02X1663135Y195902I-2560J2391D01*
G01X1663098Y195883D01*
X1663046Y195819D01*
X1662947Y195456D01*
X1662959Y195375D01*
X1662981Y195339D01*
G02X1663502Y193502I-2981J-1838D01*
G01Y193500D01*
G02X1660790Y190087I-3504J0D01*
G03X1660655Y189980I45J-195D01*
G02X1657500Y187998I-3155J1520D01*
G02X1655007Y189041I1J3502D01*
G03X1654818Y189095I-142J-141D01*
G02X1654001Y188998I-819J3405D01*
G01X1654000D01*
G02Y196002I0J3502D01*
G02X1656493Y194960I0J-3503D01*
G03X1656683Y194906I143J140D01*
G02X1656710Y194912I773J-3416D01*
G03X1656845Y195020I-45J195D01*
G02X1658365Y196598I3156J-1519D01*
G01X1658402Y196617D01*
X1658454Y196681D01*
X1658553Y197044D01*
X1658541Y197125D01*
X1658519Y197161D01*
G02X1657998Y198998I2981J1838D01*
G01Y199000D01*
G37*
G36*
G01X1811500Y182498D02*
G02Y189502I0J3502D01*
G01X1811504D01*
G02X1813544Y188845I-2J-3503D01*
G01X1813582Y188817D01*
X1813677Y188802D01*
X1814077Y188935D01*
X1814144Y189004D01*
X1814158Y189050D01*
G02X1817499Y191502I3341J-1051D01*
G01X1817500D01*
G02Y184498I0J-3502D01*
G01X1817496D01*
G02X1815456Y185155I2J3503D01*
G01X1815418Y185183D01*
X1815323Y185198D01*
X1814923Y185065D01*
X1814856Y184996D01*
X1814842Y184950D01*
G02X1811501Y182498I-3341J1051D01*
G01X1811500D01*
G37*
G36*
G01X1764498Y187260D02*
G02X1771502I3502J0D01*
G01Y187257D01*
G02X1770975Y185411I-3502J2D01*
G01X1770951Y185372D01*
X1770941Y185281D01*
X1771063Y184943D01*
G03X1771188Y184821I188J68D01*
G02X1773578Y181500I-1112J-3321D01*
G02X1773520Y180867I-3503J2D01*
G03X1773656Y180640I196J-37D01*
G02X1776102Y177300I-1057J-3340D01*
G01Y177296D01*
G02X1775687Y175644I-3503J2D01*
G03X1775681Y175466I176J-95D01*
G02X1776002Y174003I-3181J-1465D01*
G01Y174000D01*
G02X1772968Y170529I-3502J0D01*
G01X1772966D01*
G03X1772819Y170427I28J-198D01*
G01X1772663Y170145D01*
G03X1772657Y169966I176J-95D01*
G01Y169965D01*
G02X1772978Y168501I-3181J-1465D01*
G01Y168500D01*
G02X1769476Y164998I-3502J0D01*
G02X1766088Y167611I0J3503D01*
G01X1766077Y167655D01*
X1766018Y167723D01*
X1765693Y167870D01*
G03X1765520Y167865I-81J-183D01*
G01X1765519D01*
G02X1763928Y167482I-1593J3119D01*
G01X1763925D01*
G02Y174486I0J3502D01*
G02X1767313Y171873I0J-3503D01*
G01X1767324Y171829D01*
X1767383Y171761D01*
X1767708Y171614D01*
G03X1767881Y171619I81J183D01*
G01X1767882D01*
G02X1769008Y171971I1593J-3119D01*
G01X1769010D01*
G03X1769157Y172073I-28J198D01*
G01X1769313Y172355D01*
G03X1769319Y172534I-176J95D01*
G01Y172535D01*
G02X1768998Y174000I3181J1465D01*
G02X1769413Y175656I3503J2D01*
G03X1769419Y175834I-176J95D01*
G02X1769098Y177297I3181J1465D01*
G01Y177300D01*
G02X1769156Y177933I3501J-2D01*
G03X1769020Y178160I-197J36D01*
G02X1768585Y178330I1055J3340D01*
G03X1768415Y178331I-86J-180D01*
G02X1766925Y177998I-1491J3170D01*
G01X1766924D01*
G02X1766630Y178010I-4J3502D01*
G03X1766422Y177870I-17J-199D01*
G02X1763075Y175398I-3347J1030D01*
G02X1761585Y175731I1J3503D01*
G03X1761415I-85J-181D01*
G02X1759925Y175398I-1491J3170D01*
G02Y182402I0J3502D01*
G02X1761415Y182069I-1J-3503D01*
G03X1761585I85J181D01*
G02X1763075Y182402I1491J-3170D01*
G01X1763076D01*
G02X1763370Y182390I4J-3502D01*
G03X1763578Y182530I17J199D01*
G02X1765133Y184509I3347J-1030D01*
G01X1765134Y184510D01*
G03X1765227Y184644I-103J171D01*
G01X1765290Y184983D01*
X1765270Y185066D01*
X1765243Y185100D01*
G02X1764498Y187259I2757J2159D01*
G01Y187260D01*
G37*
G36*
G01X1645000Y180998D02*
G02X1643581Y181298I-1J3502D01*
G03X1643419I-81J-183D01*
G02X1642002Y180998I-1418J3202D01*
G01X1642000D01*
G02Y188002I0J3502D01*
G01X1642002D01*
G02X1643419Y187702I-1J-3502D01*
G03X1643581I81J183D01*
G02X1644998Y188002I1418J-3202D01*
G01X1645000D01*
G02X1648502Y184500I0J-3502D01*
G01Y184496D01*
G02X1648424Y183763I-3502J2D01*
G01X1648412Y183710D01*
X1648446Y183606D01*
X1648750Y183340D01*
G03X1648948Y183302I132J151D01*
G01X1648949D01*
G02X1650117Y183502I1167J-3302D01*
G02X1653620Y180000I1J-3502D01*
G02X1651680Y176865I-3503J0D01*
G01X1651633Y176842D01*
X1651575Y176757D01*
X1651533Y176315D01*
X1651575Y176220D01*
X1651616Y176189D01*
G02X1653002Y173398I-2117J-2791D01*
G02X1645998I-3502J0D01*
G01Y173400D01*
G02X1647937Y176533I3503J-1D01*
G01X1647984Y176556D01*
X1648042Y176641D01*
X1648084Y177083D01*
X1648042Y177178D01*
X1648001Y177209D01*
G02X1646614Y180000I2115J2791D01*
G02X1646693Y180737I3503J-3D01*
G01X1646705Y180790D01*
X1646671Y180894D01*
X1646367Y181160D01*
G03X1646169Y181198I-132J-151D01*
G01X1646168D01*
G02X1645000Y180998I-1167J3302D01*
G37*
G36*
G01X1619598Y178000D02*
G02X1623100Y181502I3502J0D01*
G02X1626589Y178308I0J-3503D01*
G01X1626594Y178256D01*
X1626651Y178172D01*
X1627000Y177994D01*
G03X1627194Y178001I91J178D01*
G02X1628998Y178502I1805J-3001D01*
G01X1629000D01*
G02Y171498I0J-3502D01*
G02X1627133Y172037I0J3503D01*
G01X1627132D01*
G03X1626948Y172052I-106J-169D01*
G01X1626600Y171904D01*
X1626538Y171829D01*
X1626528Y171781D01*
G02X1626437Y171437I-3427J723D01*
G01X1626424Y171397D01*
X1626433Y171313D01*
X1626625Y170983D01*
X1626693Y170934D01*
X1626735Y170925D01*
G02X1629502Y167500I-736J-3425D01*
G02X1628947Y165608I-3502J0D01*
G03Y165392I168J-108D01*
G02X1629502Y163500I-2947J-1892D01*
G02X1622498I-3502J0D01*
G02X1623053Y165392I3502J0D01*
G03Y165608I-168J108D01*
G02X1622498Y167500I2947J1892D01*
G01Y167501D01*
G02X1622663Y168563I3502J0D01*
G01X1622676Y168603D01*
X1622667Y168687D01*
X1622475Y169017D01*
X1622407Y169066D01*
X1622365Y169075D01*
G02X1619598Y172500I736J3425D01*
G02X1620615Y174968I3503J0D01*
G01X1620616Y174969D01*
G03X1620673Y175109I-143J140D01*
G01Y175391D01*
G03X1620616Y175531I-200J0D01*
G01X1620615Y175532D01*
G02X1619598Y178000I2486J2468D01*
G37*
G36*
G01X1760422Y155484D02*
G02X1760672Y156783I3503J-1D01*
G03X1760676Y156920I-186J74D01*
G02X1760498Y158025I3324J1102D01*
G02X1764000Y161528I3502J1D01*
G02X1766128Y160806I-2J-3502D01*
G03X1766372I122J159D01*
G02X1768500Y161528I2130J-2780D01*
G02X1770644Y160795I0J-3502D01*
G03X1770887Y160794I122J158D01*
G02X1772998Y161502I2111J-2794D01*
G01X1773000D01*
G02Y154498I0J-3502D01*
G01X1772998D01*
G02X1771115Y155048I1J3502D01*
G01X1771074Y155075D01*
X1770975Y155083D01*
X1770626Y154934D01*
G03X1770508Y154790I78J-184D01*
G02X1767075Y151982I-3433J695D01*
G02X1765585Y152315I1J3503D01*
G03X1765415I-85J-181D01*
G02X1763925Y151982I-1491J3170D01*
G01X1763923D01*
G02X1760422Y155484I1J3502D01*
G37*
G36*
G01X1764000Y146028D02*
G02X1766128Y145306I-2J-3502D01*
G03X1766372I122J159D01*
G02X1768500Y146028I2130J-2780D01*
G02X1770628Y145306I-2J-3502D01*
G03X1770872I122J159D01*
G02X1773000Y146028I2130J-2780D01*
G02X1776502Y142525I-1J-3503D01*
G02X1773946Y139153I-3502J0D01*
G01X1773945D01*
G03X1773817Y139041I55J-192D01*
G01X1773693Y138757D01*
G03X1773698Y138587I183J-80D01*
G01Y138586D01*
G02X1774078Y137000I-3123J-1587D01*
G02X1770575Y133498I-3503J1D01*
G02X1769085Y133831I1J3503D01*
G03X1768915I-85J-181D01*
G02X1767425Y133498I-1491J3170D01*
G01X1767423D01*
G02X1763922Y137000I1J3502D01*
G02X1764240Y138458I3503J0D01*
G01X1764261Y138503D01*
X1764255Y138603D01*
X1764054Y138929D01*
G03X1763889Y139024I-170J-105D01*
G02X1760498Y142525I112J3501D01*
G01Y142527D01*
G02X1764000Y146028I3502J-1D01*
G37*
G36*
G01X1710602Y142500D02*
G02X1708443Y139265I-3503J0D01*
G03X1708335Y139157I77J-185D01*
G02X1705100Y136998I-3235J1344D01*
G02X1701598Y140500I0J3502D01*
G02X1703757Y143735I3503J0D01*
G03X1703865Y143843I-77J185D01*
G02X1707100Y146002I3235J-1344D01*
G02X1710602Y142500I0J-3502D01*
G37*
G36*
G01X1710942Y131942D02*
Y132058D01*
G03X1710892Y132190I-200J0D01*
G02X1710022Y134500I2633J2310D01*
G02X1717028I3503J0D01*
G02X1716158Y132190I-3503J0D01*
G03X1716108Y132058I150J-132D01*
G01Y131942D01*
G03X1716158Y131810I200J0D01*
G02X1717028Y129500I-2633J-2310D01*
G02X1710022I-3503J0D01*
G02X1710892Y131810I3503J0D01*
G03X1710942Y131942I-150J132D01*
G37*
G36*
G01X1681498Y133000D02*
G02X1688502I3502J0D01*
G01Y132998D01*
G02X1687453Y130500I-3502J1D01*
G03X1687393Y130354I140J-143D01*
G01X1687396Y130232D01*
G03X1687461Y130087I200J3D01*
G02X1687476Y130074I-2286J-2653D01*
G03X1687606Y130021I136J147D01*
G01X1687723Y130018D01*
G03X1687857Y130064I6J200D01*
G02X1690100Y130878I2245J-2688D01*
G02Y123872I0J-3503D01*
G02X1687724Y124801I0J3503D01*
G03X1687594Y124854I-136J-147D01*
G01X1687477Y124857D01*
G03X1687343Y124811I-6J-200D01*
G02X1685846Y124078I-2244J2689D01*
G01X1685844D01*
G03X1685706Y123966I44J-195D01*
G01X1685572Y123674D01*
G03X1685578Y123497I182J-82D01*
G01Y123496D01*
G02X1686002Y121825I-3078J-1670D01*
G02X1682500Y118322I-3502J-1D01*
G02X1679843Y119543I1J3503D01*
G01X1679842Y119544D01*
G03X1679650Y119609I-151J-131D01*
G01X1679306Y119536D01*
G03X1679156Y119397I42J-196D01*
G02X1675800Y116898I-3356J1004D01*
G01X1675798D01*
G02X1674381Y117198I1J3502D01*
G03X1674219I-81J-183D01*
G02X1672800Y116898I-1418J3202D01*
G02X1671381Y117198I-1J3502D01*
G03X1671219I-81J-183D01*
G02X1669802Y116898I-1418J3202D01*
G01X1669800D01*
G02Y123902I0J3502D01*
G01X1669802D01*
G02X1671219Y123602I-1J-3502D01*
G03X1671381I81J183D01*
G02X1672800Y123902I1418J-3202D01*
G02X1674219Y123602I1J-3502D01*
G03X1674381I81J183D01*
G02X1675798Y123902I1418J-3202D01*
G01X1675800D01*
G02X1678457Y122682I0J-3503D01*
G01X1678458Y122681D01*
G03X1678650Y122616I151J131D01*
G01X1678994Y122689D01*
G03X1679144Y122828I-42J196D01*
G02X1681754Y125247I3356J-1003D01*
G01X1681756D01*
G03X1681894Y125359I-44J195D01*
G01X1682028Y125651D01*
G03X1682022Y125828I-182J82D01*
G01Y125829D01*
G02X1681598Y127500I3078J1670D01*
G02X1682571Y129923I3502J0D01*
G01X1682572Y129924D01*
G03X1682627Y130065I-145J138D01*
G01X1682621Y130347D01*
G03X1682562Y130486I-200J-3D01*
G01X1682561Y130487D01*
G02X1681498Y133000I2439J2513D01*
G37*
G36*
G01X1611517Y127441D02*
Y127559D01*
G03X1611467Y127690I-200J-1D01*
G02X1610598Y130000I2634J2309D01*
G02X1617602I3502J0D01*
G02X1616733Y127690I-3503J-1D01*
G03X1616683Y127559I150J-132D01*
G01Y127441D01*
G03X1616733Y127310I200J1D01*
G02Y122690I-2634J-2310D01*
G03X1616683Y122559I150J-132D01*
G01Y122441D01*
G03X1616733Y122310I200J1D01*
G02Y117690I-2634J-2310D01*
G03X1616683Y117559I150J-132D01*
G01Y117441D01*
G03X1616733Y117310I200J1D01*
G02Y112690I-2634J-2310D01*
G03X1616683Y112559I150J-132D01*
G01Y112441D01*
G03X1616733Y112310I200J1D01*
G02X1617602Y110000I-2634J-2309D01*
G02X1610598I-3502J0D01*
G02X1611467Y112310I3503J1D01*
G03X1611517Y112441I-150J132D01*
G01Y112559D01*
G03X1611467Y112690I-200J-1D01*
G02Y117310I2634J2310D01*
G03X1611517Y117441I-150J132D01*
G01Y117559D01*
G03X1611467Y117690I-200J-1D01*
G02Y122310I2634J2310D01*
G03X1611517Y122441I-150J132D01*
G01Y122559D01*
G03X1611467Y122690I-200J-1D01*
G02Y127310I2634J2310D01*
G03X1611517Y127441I-150J132D01*
G37*
G36*
G01X1651325Y128578D02*
X1651329D01*
G02X1652794Y128256I-2J-3502D01*
G01X1652832Y128238D01*
X1652918Y128237D01*
X1653270Y128388D01*
X1653327Y128450D01*
X1653340Y128490D01*
G02X1656657Y130868I3317J-1124D01*
G02Y123862I0J-3503D01*
G02X1655188Y124185I0J3502D01*
G01X1655150Y124203D01*
X1655064Y124204D01*
X1654712Y124053D01*
X1654655Y123991D01*
X1654642Y123951D01*
G02X1654337Y123288I-3317J1124D01*
G03X1654319Y123124I172J-102D01*
G02X1654492Y122036I-3329J-1087D01*
G01Y122034D01*
G02X1650990Y118532I-3502J0D01*
G01X1650987D01*
G02X1649721Y118769I0J3502D01*
G03X1649551Y118757I-72J-186D01*
G02X1647839Y118310I-1712J3055D01*
G01X1647837D01*
G02X1644758Y120142I0J3503D01*
G03X1644620Y120243I-176J-95D01*
G01X1644318Y120302D01*
G03X1644153Y120261I-39J-196D01*
G02X1641932Y119466I-2222J2708D01*
G02X1638429Y122969I0J3503D01*
G02X1641930Y126472I3503J0D01*
G01X1641934D01*
G02X1641968Y126471I-86J-3501D01*
G02X1644917Y128084I2949J-1889D01*
G02X1647640Y126784I0J-3502D01*
G01X1647671Y126746D01*
X1647761Y126707D01*
X1648188Y126740D01*
X1648272Y126793D01*
X1648296Y126835D01*
G02X1651325Y128578I3029J-1760D01*
G37*
G36*
G01X1710941Y116941D02*
Y117059D01*
G03X1710891Y117190I-200J-1D01*
G02X1710022Y119500I2634J2309D01*
G02X1717026I3502J0D01*
G02X1716157Y117190I-3503J-1D01*
G03X1716107Y117059I150J-132D01*
G01Y116942D01*
G03X1716157Y116810I200J0D01*
G02X1716915Y115377I-2633J-2310D01*
G03X1717027Y115245I193J51D01*
G01X1717353Y115098D01*
X1717444Y115100D01*
X1717484Y115120D01*
G02X1719075Y115502I1591J-3120D01*
G02X1722578Y112000I1J-3502D01*
G02X1721665Y109643I-3503J1D01*
G03Y109373I148J-135D01*
G02X1722578Y107016I-2590J-2358D01*
G02X1719075Y103514I-3503J1D01*
G02X1715687Y106127I0J3503D01*
G01X1715676Y106171D01*
X1715617Y106239D01*
X1715292Y106386D01*
G03X1715119Y106381I-81J-183D01*
G01X1715118D01*
G02X1713527Y105998I-1593J3119D01*
G01X1713524D01*
G02X1710022Y109500I0J3502D01*
G02X1710891Y111810I3503J1D01*
G03X1710941Y111941I-150J132D01*
G01Y112059D01*
G03X1710891Y112190I-200J-1D01*
G02Y116810I2634J2310D01*
G03X1710941Y116941I-150J132D01*
G37*
G36*
G01X1696600Y115498D02*
G02X1700102Y119000I0J3502D01*
G02X1699993Y118129I-3503J-4D01*
G01X1699980Y118078D01*
X1700007Y117976D01*
X1700326Y117657D01*
X1700428Y117630D01*
X1700479Y117643D01*
G02X1701350Y117752I867J-3394D01*
G02X1697848Y114250I0J-3502D01*
G02X1697957Y115121I3503J4D01*
G01X1697970Y115172D01*
X1697943Y115274D01*
X1697624Y115593D01*
X1697522Y115620D01*
X1697471Y115607D01*
G02X1696600Y115498I-867J3394D01*
G37*
G36*
G01X1618792Y114940D02*
G02X1619348Y116832I3503J-2D01*
G03Y117048I-169J108D01*
G02X1618792Y118940I2947J1894D01*
G02X1625798I3503J0D01*
G02X1625242Y117048I-3503J2D01*
G03Y116832I169J-108D01*
G02X1625798Y114940I-2947J-1894D01*
G02X1618792I-3503J0D01*
G37*
G36*
G01X1629870Y100738D02*
X1629866D01*
G02X1629571Y100751I7J3502D01*
G03X1629539I-16J-200D01*
G02X1629270Y100740I-277J3489D01*
G02X1627656Y101135I1J3500D01*
G03X1627445Y101119I-93J-177D01*
G02X1625370Y100438I-2075J2821D01*
G02Y107442I0J3502D01*
G01X1625372D01*
G02X1626988Y107046I-2J-3502D01*
G03X1627199Y107062I93J177D01*
G02X1628646Y107684I2070J-2822D01*
G03X1628780Y107775I-36J197D01*
G01X1628937Y108025D01*
G03X1628960Y108183I-170J105D01*
G01Y108184D01*
G02X1628834Y109113I3376J931D01*
G01Y109117D01*
G02X1629731Y111458I3503J0D01*
G03X1629779Y111624I-149J133D01*
G01X1629719Y111979D01*
X1629666Y112053D01*
X1629627Y112075D01*
G02X1627820Y115140I1696J3065D01*
G02X1634826I3503J0D01*
G02X1633928Y112799I-3503J1D01*
G01X1633897Y112764D01*
X1633872Y112678D01*
X1633940Y112278D01*
X1633993Y112204D01*
X1634032Y112182D01*
G02X1635838Y109119I-1696J-3064D01*
G01Y109117D01*
G02X1633461Y105800I-3503J0D01*
G01X1633424Y105787D01*
X1633365Y105737D01*
X1633202Y105415D01*
X1633196Y105338D01*
X1633208Y105300D01*
G02X1633372Y104242I-3338J-1059D01*
G01Y104240D01*
G02X1629870Y100738I-3502J0D01*
G37*
G36*
G01X1485918Y117276D02*
G02X1487337Y116975I-2J-3503D01*
G03X1487499I81J183D01*
G02X1488918Y117276I1421J-3202D01*
G02X1490337Y116975I-2J-3503D01*
G03X1490499I81J183D01*
G02X1491918Y117276I1421J-3202D01*
G02X1495420Y113773I-1J-3503D01*
G01Y113771D01*
G02X1495120Y112354I-3502J1D01*
G03Y112192I183J-81D01*
G02X1495420Y110773I-3202J-1418D01*
G02X1495120Y109354I-3502J-1D01*
G03Y109192I183J-81D01*
G02X1495420Y107773I-3202J-1418D01*
G02X1495120Y106354I-3502J-1D01*
G03Y106192I183J-81D01*
G02X1495420Y104773I-3202J-1418D01*
G02X1491918Y101270I-3502J-1D01*
G02X1490499Y101571I2J3503D01*
G03X1490337I-81J-183D01*
G02X1488918Y101270I-1421J3202D01*
G02X1487499Y101571I2J3503D01*
G03X1487337I-81J-183D01*
G02X1485918Y101270I-1421J3202D01*
G02X1484499Y101571I2J3503D01*
G03X1484337I-81J-183D01*
G02X1482918Y101270I-1421J3202D01*
G02X1479416Y104773I1J3503D01*
G01Y104775D01*
G02X1479716Y106192I3502J-1D01*
G03Y106354I-183J81D01*
G02X1479416Y107773I3202J1418D01*
G02X1479716Y109192I3502J1D01*
G03Y109354I-183J81D01*
G02X1479416Y110773I3202J1418D01*
G02X1479716Y112192I3502J1D01*
G03Y112354I-183J81D01*
G02X1479416Y113773I3202J1418D01*
G02X1482918Y117276I3502J1D01*
G02X1484337Y116975I-2J-3503D01*
G03X1484499I81J183D01*
G02X1485918Y117276I1421J-3202D01*
G37*
G36*
G01X1527100Y104998D02*
G02X1523631Y108014I0J3503D01*
G03X1523496Y108176I-198J-28D01*
G02X1521098Y111500I1105J3324D01*
G02X1524600Y115002I3502J0D01*
G02X1528069Y111986I0J-3503D01*
G03X1528204Y111824I198J28D01*
G02X1530602Y108500I-1105J-3324D01*
G02X1527100Y104998I-3502J0D01*
G37*
G36*
G01X1662000Y109502D02*
G02Y102498I0J-3502D01*
G01X1661999D01*
G02X1661058Y102627I1J3502D01*
G01X1661057D01*
G03X1660886Y102596I-53J-193D01*
G01X1660632Y102410D01*
G03X1660550Y102257I118J-162D01*
G01Y102256D01*
G02X1657050Y98878I-3500J124D01*
G01X1657049D01*
G02X1655113Y99462I0J3502D01*
G01X1655070Y99490D01*
X1654969Y99499D01*
X1654614Y99342D01*
G03X1654497Y99190I81J-183D01*
G02X1651037Y96232I-3460J545D01*
G02X1648036Y97928I0J3503D01*
G03X1647820Y98020I-171J-103D01*
G02X1647037Y97932I-780J3414D01*
G02X1645381Y98347I-2J3502D01*
G03X1645193I-94J-176D01*
G02X1643537Y97932I-1654J3087D01*
G02X1641881Y98347I-2J3502D01*
G03X1641693I-94J-176D01*
G02X1640039Y97932I-1654J3087D01*
G01X1640037D01*
G02X1636545Y101165I0J3502D01*
G03X1636464Y101311I-200J-15D01*
G02X1635034Y104134I2071J2823D01*
G02X1638537Y107636I3503J-1D01*
G01X1638539D01*
G02X1640193Y107221I0J-3502D01*
G03X1640381I94J176D01*
G02X1642037Y107636I1654J-3087D01*
G02X1643693Y107221I2J-3502D01*
G03X1643881I94J176D01*
G02X1645535Y107636I1654J-3087D01*
G01X1645537D01*
G02X1649029Y104403I0J-3502D01*
G03X1649110Y104257I200J15D01*
G02X1650038Y103240I-2073J-2823D01*
G03X1650254Y103148I171J103D01*
G02X1651037Y103236I780J-3414D01*
G02X1652974Y102652I1J-3502D01*
G01X1653017Y102624D01*
X1653118Y102615D01*
X1653473Y102772D01*
G03X1653590Y102924I-81J183D01*
G02X1657050Y105882I3460J-545D01*
G01X1657051D01*
G02X1657992Y105753I-1J-3502D01*
G01X1657993D01*
G03X1658164Y105784I53J193D01*
G01X1658418Y105970D01*
G03X1658500Y106123I-118J162D01*
G01Y106124D01*
G02X1662000Y109502I3500J-124D01*
G37*
G36*
G01X1715172Y99000D02*
G02X1718675Y102502I3503J-1D01*
G02X1722133Y99554I0J-3502D01*
G03X1722296Y99389I197J32D01*
G02X1725188Y95940I-611J-3449D01*
G02X1722140Y92467I-3503J0D01*
G03X1721978Y92335I27J-198D01*
G02X1721160Y91032I-3303J1165D01*
G01X1721159Y91031D01*
G03X1721102Y90891I143J-140D01*
G01Y90609D01*
G03X1721159Y90469I200J0D01*
G01X1721160Y90468D01*
G02X1722178Y88000I-2485J-2469D01*
G02X1715172I-3503J0D01*
G02X1716190Y90468I3503J-1D01*
G01X1716191Y90469D01*
G03X1716248Y90609I-143J140D01*
G01Y90891D01*
G03X1716191Y91031I-200J0D01*
G01X1716190Y91032D01*
G02X1715172Y93500I2485J2469D01*
G02X1716190Y95968I3503J-1D01*
G01X1716191Y95969D01*
G03X1716248Y96109I-143J140D01*
G01Y96391D01*
G03X1716191Y96531I-200J0D01*
G01X1716190Y96532D01*
G02X1715172Y99000I2485J2469D01*
G37*
G36*
G01X1531600Y93438D02*
G02X1528415Y95483I0J3503D01*
G03X1528172Y95591I-182J-82D01*
G02X1527100Y95422I-1075J3334D01*
G02Y102428I0J3503D01*
G02X1530285Y100383I0J-3503D01*
G03X1530528Y100275I182J82D01*
G02X1531600Y100444I1075J-3334D01*
G02Y93438I0J-3503D01*
G37*
G36*
G01X1602100Y92502D02*
G02X1603992Y91947I0J-3502D01*
G03X1604208I108J168D01*
G02X1606100Y92502I1892J-2947D01*
G01X1606102D01*
G02X1607519Y92202I-1J-3502D01*
G03X1607681I81J183D01*
G02X1609098Y92502I1418J-3202D01*
G01X1609100D01*
G02X1612602Y89000I0J-3502D01*
G01Y88998D01*
G02X1612187Y87344I-3502J0D01*
G03Y87156I176J-94D01*
G02X1612602Y85500I-3087J-1654D01*
G01Y85430D01*
Y85426D01*
X1612601Y85366D01*
X1612667Y85264D01*
X1613126Y85072D01*
X1613245Y85097D01*
X1613288Y85141D01*
G02X1615800Y86202I2511J-2441D01*
G02X1617219Y85902I1J-3502D01*
G03X1617381I81J183D01*
G02X1618798Y86202I1418J-3202D01*
G01X1618800D01*
G02X1622302Y82700I0J-3502D01*
G01Y82698D01*
G02X1622002Y81281I-3502J1D01*
G03Y81119I183J-81D01*
G02X1622302Y79700I-3202J-1418D01*
G02X1622002Y78281I-3502J-1D01*
G03Y78119I183J-81D01*
G02X1622302Y76702I-3202J-1418D01*
G01Y76700D01*
G02X1618800Y73198I-3502J0D01*
G01X1618798D01*
G02X1617381Y73498I1J3502D01*
G03X1617219I-81J-183D01*
G02X1615802Y73198I-1418J3202D01*
G01X1615800D01*
G02X1612298Y76700I0J3502D01*
G01Y76702D01*
G02X1612598Y78119I3502J-1D01*
G03Y78281I-183J81D01*
G02X1612316Y79341I3202J1419D01*
G03X1612182Y79510I-199J-20D01*
G01X1611838Y79628D01*
G03X1611630Y79578I-65J-189D01*
G01X1611629Y79577D01*
G02X1609100Y78498I-2529J2424D01*
G01X1609098D01*
G02X1607681Y78798I1J3502D01*
G03X1607519I-81J-183D01*
G02X1606102Y78498I-1418J3202D01*
G01X1606100D01*
G02X1604208Y79053I0J3502D01*
G03X1603992I-108J-168D01*
G02X1602100Y78498I-1892J2947D01*
G02X1598598Y82000I0J3502D01*
G01Y82002D01*
G02X1599013Y83656I3502J0D01*
G03Y83844I-176J94D01*
G02X1598598Y85500I3087J1654D01*
G02X1599013Y87156I3502J2D01*
G03Y87344I-176J94D01*
G02X1598598Y88998I3087J1654D01*
G01Y89000D01*
G02X1602100Y92502I3502J0D01*
G37*
G36*
G01X1486498Y80500D02*
Y80502D01*
G02X1486913Y82156I3502J0D01*
G03Y82344I-176J94D01*
G02X1486498Y83998I3087J1654D01*
G01Y84000D01*
G02X1490000Y87502I3502J0D01*
G01X1490002D01*
G02X1492519Y86434I-1J-3502D01*
G03X1492775Y86407I144J139D01*
G02X1494728Y87002I1953J-2908D01*
G02Y79998I0J-3502D01*
G02X1493915Y80094I1J3502D01*
G01X1493912D01*
G03X1493761Y80068I-44J-195D01*
G01X1493483Y79893D01*
X1493437Y79826D01*
X1493429Y79786D01*
G02X1490000Y76998I-3429J715D01*
G02X1486498Y80500I0J3502D01*
G37*
G36*
G01X1644298Y80200D02*
G02X1644598Y81619I3502J1D01*
G03Y81781I-183J81D01*
G02X1644298Y83198I3202J1418D01*
G01Y83200D01*
G02X1651302I3502J0D01*
G01Y83198D01*
G02X1651002Y81781I-3502J1D01*
G03Y81619I183J-81D01*
G02X1651302Y80200I-3202J-1418D01*
G02X1651002Y78781I-3502J-1D01*
G03Y78619I183J-81D01*
G02X1651302Y77202I-3202J-1418D01*
G01Y77200D01*
G02X1644298I-3502J0D01*
G01Y77202D01*
G02X1644598Y78619I3502J-1D01*
G03Y78781I-183J81D01*
G02X1644298Y80200I3202J1418D01*
G37*
G36*
G01X317000Y77978D02*
G02X319128Y77256I-2J-3502D01*
G03X319372I122J159D01*
G02X320499Y77831I2129J-2781D01*
G03X320634Y77968I-57J192D01*
G02X324000Y80502I3366J-969D01*
G02X327418Y77765I0J-3503D01*
G03X327526Y77629I195J44D01*
G02X328128Y77257I-1531J-3150D01*
G03X328372I122J159D01*
G02X330499Y77978I2128J-2781D01*
G01X330500D01*
G02Y70974I0J-3502D01*
G01X330499D01*
G02X328372Y71695I1J3502D01*
G03X328128I-122J-159D01*
G02X326000Y70974I-2128J2781D01*
G02X323873Y71694I0J3502D01*
G03X323630I-121J-159D01*
G02X321500Y70972I-2130J2781D01*
G02X319372Y71694I2J3502D01*
G03X319128I-122J-159D01*
G02X317000Y70972I-2130J2780D01*
G02Y77978I0J3503D01*
G37*
G36*
G01X1695500Y72998D02*
X1695498D01*
G02X1693782Y73448I1J3502D01*
G03X1693593Y73451I-97J-175D01*
G02X1692001Y73068I-1592J3119D01*
G01X1692000D01*
G02Y80072I0J3502D01*
G01X1692002D01*
G02X1693718Y79622I-1J-3502D01*
G03X1693907Y79619I97J175D01*
G02X1695499Y80002I1592J-3119D01*
G01X1695500D01*
G02Y72998I0J-3502D01*
G37*
G36*
G01X1503728Y70974D02*
G02X1501585Y71706I0J3503D01*
G03X1501342Y71707I-122J-158D01*
G02X1499230Y70998I-2113J2793D01*
G01X1499228D01*
G02Y78002I0J3502D01*
G01X1499231D01*
G02X1501371Y77271I-2J-3503D01*
G03X1501614Y77270I122J158D01*
G02X1503728Y77980I2114J-2793D01*
G02Y70974I0J-3503D01*
G37*
G36*
G01X1602100Y73002D02*
G02X1603992Y72447I0J-3502D01*
G03X1604208I108J168D01*
G02X1606100Y73002I1892J-2947D01*
G01X1606102D01*
G02X1607519Y72702I-1J-3502D01*
G03X1607681I81J183D01*
G02X1609098Y73002I1418J-3202D01*
G01X1609100D01*
G02X1612602Y69500I0J-3502D01*
G01Y69498D01*
G02X1612187Y67844I-3502J0D01*
G03Y67656I176J-94D01*
G02X1612602Y66000I-3087J-1654D01*
G02X1612187Y64344I-3502J-2D01*
G03Y64156I176J-94D01*
G02X1612602Y62502I-3087J-1654D01*
G01Y62500D01*
G02X1609100Y58998I-3502J0D01*
G01X1609098D01*
G02X1607681Y59298I1J3502D01*
G03X1607519I-81J-183D01*
G02X1606102Y58998I-1418J3202D01*
G01X1606100D01*
G02X1604208Y59553I0J3502D01*
G03X1603992I-108J-168D01*
G02X1602100Y58998I-1892J2947D01*
G02X1598598Y62500I0J3502D01*
G01Y62502D01*
G02X1599013Y64156I3502J0D01*
G03Y64344I-176J94D01*
G02X1598598Y66000I3087J1654D01*
G02X1599013Y67656I3502J2D01*
G03Y67844I-176J94D01*
G02X1598598Y69498I3087J1654D01*
G01Y69500D01*
G02X1602100Y73002I3502J0D01*
G37*
G36*
G01X1494554Y63002D02*
G02X1492600Y63719I175J3498D01*
G03X1492356I-122J-159D01*
G02X1490229Y62998I-2128J2781D01*
G01X1490228D01*
G02Y70002I0J3502D01*
G01X1490229D01*
G02X1492356Y69281I-1J-3502D01*
G03X1492600I122J159D01*
G02X1494727Y70002I2128J-2781D01*
G01X1494728D01*
G02X1498167Y67160I0J-3502D01*
G03X1498354Y66998I196J38D01*
G02X1501063Y65489I-174J-3498D01*
G01X1501095Y65442D01*
X1501199Y65397D01*
X1501611Y65456D01*
G03X1501772Y65591I-29J198D01*
G01Y65592D01*
G02X1505100Y68002I3328J-1093D01*
G02Y60998I0J-3502D01*
G02X1502217Y62511I0J3503D01*
G01X1502185Y62558D01*
X1502081Y62603D01*
X1501669Y62544D01*
G03X1501508Y62409I29J-198D01*
G01Y62408D01*
G02X1498180Y59998I-3328J1093D01*
G02X1494741Y62840I0J3502D01*
G03X1494554Y63002I-196J-38D01*
G37*
G36*
G01X313498Y64500D02*
G02X317000Y68002I3502J0D01*
G01X317001D01*
G02X318066Y67836I0J-3502D01*
G03X318309Y67944I61J191D01*
G02X321500Y70002I3191J-1445D01*
G02X324813Y67636I0J-3503D01*
G03X325007Y67501I189J65D01*
G02X325100Y67502I84J-3501D01*
G02Y60498I0J-3502D01*
G01X325096D01*
G02X323842Y60731I2J3502D01*
G03X323621Y60677I-71J-187D01*
G02X321000Y59498I-2621J2324D01*
G02X320769Y59505I-9J3502D01*
G01X320720Y59508D01*
X320631Y59469D01*
X320363Y59136D01*
X320345Y59040D01*
X320359Y58993D01*
G02X320502Y58005I-3359J-991D01*
G01Y58000D01*
G02X313498I-3502J0D01*
G01Y58001D01*
G02X315061Y60917I3502J0D01*
G01X315102Y60945D01*
X315150Y61033D01*
Y61467D01*
X315102Y61555D01*
X315061Y61583D01*
G02X313498Y64499I1939J2916D01*
G01Y64500D01*
G37*
G36*
G01X1419310Y43984D02*
G02X1420729Y43683I-2J-3503D01*
G03X1420891I81J183D01*
G02X1422310Y43984I1421J-3202D01*
G02X1423729Y43683I-2J-3503D01*
G03X1423891I81J183D01*
G02X1425310Y43984I1421J-3202D01*
G02Y36978I0J-3503D01*
G02X1423891Y37279I2J3503D01*
G03X1423729I-81J-183D01*
G02X1422310Y36978I-1421J3202D01*
G02X1420891Y37279I2J3503D01*
G03X1420729I-81J-183D01*
G02X1419310Y36978I-1421J3202D01*
G02X1417891Y37279I2J3503D01*
G03X1417729I-81J-183D01*
G02X1416310Y36978I-1421J3202D01*
G02Y43984I0J3503D01*
G02X1417729Y43683I-2J-3503D01*
G03X1417891I81J183D01*
G02X1419310Y43984I1421J-3202D01*
G37*
G36*
G01X317766Y42714D02*
G02X319185Y42413I-2J-3503D01*
G03X319347I81J183D01*
G02X320766Y42714I1421J-3202D01*
G02X322185Y42413I-2J-3503D01*
G03X322347I81J183D01*
G02X323766Y42714I1421J-3202D01*
G02Y35708I0J-3503D01*
G02X322347Y36009I2J3503D01*
G03X322185I-81J-183D01*
G02X320766Y35708I-1421J3202D01*
G02X319347Y36009I2J3503D01*
G03X319185I-81J-183D01*
G02X317766Y35708I-1421J3202D01*
G02X316347Y36009I2J3503D01*
G03X316185I-81J-183D01*
G02X314766Y35708I-1421J3202D01*
G02Y42714I0J3503D01*
G02X316185Y42413I-2J-3503D01*
G03X316347I81J183D01*
G02X317766Y42714I1421J-3202D01*
G37*
G36*
G01X1352310Y42396D02*
G02X1353729Y42095I-2J-3503D01*
G03X1353891I81J183D01*
G02X1355310Y42396I1421J-3202D01*
G02X1356729Y42095I-2J-3503D01*
G03X1356891I81J183D01*
G02X1358310Y42396I1421J-3202D01*
G02Y35390I0J-3503D01*
G02X1356891Y35691I2J3503D01*
G03X1356729I-81J-183D01*
G02X1355310Y35390I-1421J3202D01*
G02X1353891Y35691I2J3503D01*
G03X1353729I-81J-183D01*
G02X1352310Y35390I-1421J3202D01*
G02X1350891Y35691I2J3503D01*
G03X1350729I-81J-183D01*
G02X1349310Y35390I-1421J3202D01*
G02Y42396I0J3503D01*
G02X1350729Y42095I-2J-3503D01*
G03X1350891I81J183D01*
G02X1352310Y42396I1421J-3202D01*
G37*
G36*
G01X1310366Y41984D02*
G02X1311785Y41684I1J-3502D01*
G03X1311947I81J183D01*
G02X1313366Y41984I1418J-3202D01*
G02X1314785Y41684I1J-3502D01*
G03X1314947I81J183D01*
G02X1316364Y41984I1418J-3202D01*
G01X1316366D01*
G02Y34980I0J-3502D01*
G01X1316364D01*
G02X1314947Y35280I1J3502D01*
G03X1314785I-81J-183D01*
G02X1313366Y34980I-1418J3202D01*
G02X1311947Y35280I-1J3502D01*
G03X1311785I-81J-183D01*
G02X1310366Y34980I-1418J3202D01*
G02X1308947Y35280I-1J3502D01*
G03X1308785I-81J-183D01*
G02X1307368Y34980I-1418J3202D01*
G01X1307366D01*
G02Y41984I0J3502D01*
G01X1307368D01*
G02X1308785Y41684I-1J-3502D01*
G03X1308947I81J183D01*
G02X1310366Y41984I1418J-3202D01*
G37*
G36*
G01X1431417Y23264D02*
G02X1436375Y21472I1J-7753D01*
G03X1436700Y21593I128J154D01*
G02X1441417Y25606I4717J-766D01*
G02Y16048I0J-4779D01*
G02X1439413Y16489I1J4779D01*
G03X1439130Y16288I-84J-181D01*
G02X1439169Y15512I-7713J-777D01*
G02X1431417Y23264I-7752J0D01*
G37*
G36*
G01X1726171Y160576D02*
X1726018Y160913D01*
X1725959Y160968D01*
X1725920Y160982D01*
G02X1723598Y164280I1181J3298D01*
G02X1730602I3502J0D01*
G02X1730354Y162984I-3502J-2D01*
G01X1730339Y162946D01*
X1730340Y162865D01*
X1730493Y162528D01*
X1730552Y162473D01*
X1730591Y162459D01*
G02X1732914Y159161I-1180J-3298D01*
G02X1729411Y155658I-3503J0D01*
G02X1729293Y155660I0J3503D01*
G01X1729236Y155662D01*
X1729138Y155606D01*
X1728914Y155189D01*
X1728921Y155076D01*
X1728954Y155029D01*
G02X1729602Y153000I-2855J-2030D01*
G02X1722596I-3503J0D01*
G02X1722597Y153055I3502J-36D01*
G01X1722598Y153097D01*
X1722567Y153172D01*
X1722300Y153434D01*
X1722225Y153463D01*
X1722183Y153462D01*
G02X1722063Y153460I-118J3500D01*
G02X1719329Y154773I0J3503D01*
G03X1719088Y154829I-156J-125D01*
G02X1718999Y154789I-1480J3174D01*
G01X1718963Y154773D01*
X1718910Y154719D01*
X1718773Y154390D01*
X1718772Y154314D01*
X1718787Y154277D01*
G02X1719028Y153000I-3263J-1277D01*
G02X1715525Y149498I-3503J1D01*
G02X1713858Y149920I0J3502D01*
G03X1713667I-96J-176D01*
G02X1712000Y149498I-1667J3080D01*
G02X1708498Y153000I0J3502D01*
G02X1708701Y154177I3502J2D01*
G01X1708715Y154215D01*
X1708711Y154295D01*
X1708553Y154624D01*
X1708494Y154677D01*
X1708455Y154690D01*
G02X1706098Y158000I1146J3310D01*
G02X1713102I3502J0D01*
G02X1712899Y156823I-3502J-2D01*
G01X1712885Y156785D01*
X1712889Y156705D01*
X1713047Y156376D01*
X1713106Y156323D01*
X1713145Y156310D01*
G02X1713667Y156080I-1146J-3309D01*
G03X1713858I96J176D01*
G02X1714126Y156211I1671J-3078D01*
G01X1714162Y156227D01*
X1714215Y156281D01*
X1714352Y156610D01*
X1714353Y156686D01*
X1714338Y156723D01*
G02X1714098Y158000I3263J1274D01*
G02X1717600Y161502I3502J0D01*
G02X1720334Y160189I0J-3503D01*
G03X1720575Y160133I156J125D01*
G02X1722063Y160464I1486J-3171D01*
G02X1725566Y156962I1J-3502D01*
G02X1725565Y156907I-3502J36D01*
G01X1725564Y156865D01*
X1725595Y156790D01*
X1725862Y156528D01*
X1725937Y156499D01*
X1725979Y156500D01*
G02X1726099Y156502I118J-3500D01*
G02X1726217Y156501I29J-3502D01*
G01X1726274Y156499D01*
X1726372Y156555D01*
X1726596Y156972D01*
X1726589Y157085D01*
X1726556Y157132D01*
G02X1725908Y159161I2855J2030D01*
G02X1726157Y160457I3503J-1D01*
G01X1726172Y160495D01*
X1726171Y160576D01*
G37*
G36*
G01X1730445Y171934D02*
X1730330Y171962D01*
G03X1730184Y171943I-49J-194D01*
G02X1728475Y171498I-1708J3057D01*
G02Y178502I0J3502D01*
G02X1731410Y176911I0J-3503D01*
G03X1731530Y176826I168J109D01*
G01X1731645Y176798D01*
G03X1731791Y176817I49J194D01*
G02X1733500Y177262I1708J-3057D01*
G02Y170258I0J-3502D01*
G02X1730565Y171849I0J3503D01*
G03X1730445Y171934I-168J-109D01*
G37*
G36*
G01X1723086Y177389D02*
G02X1724026Y175000I-2563J-2388D01*
G02X1717022I-3502J0D01*
G02X1717561Y176868I3502J1D01*
G03X1717538Y177111I-169J107D01*
G02X1716598Y179500I2563J2388D01*
G02X1723602I3502J0D01*
G02X1723063Y177632I-3502J-1D01*
G03X1723086Y177389I169J-107D01*
G37*
G36*
G01X1683549Y183568D02*
X1683548Y183931D01*
X1683519Y184003D01*
X1683490Y184031D01*
G02X1682472Y186500I2485J2469D01*
G02X1685975Y190002I3503J-1D01*
G02X1689304Y187588I0J-3502D01*
G03X1689419Y187465I190J62D01*
G02X1691602Y184220I-1320J-3245D01*
G02X1689478Y181000I-3503J0D01*
G02X1688461Y178532I-3503J0D01*
G01X1688433Y178503D01*
X1688403Y178431D01*
Y178069D01*
X1688433Y177997D01*
X1688461Y177968D01*
G02X1689357Y176415I-2485J-2469D01*
G03X1689472Y176283I193J52D01*
G02X1691602Y173060I-1372J-3222D01*
G02X1689582Y169887I-3502J0D01*
G03X1689467Y169721I85J-181D01*
G02X1688461Y167532I-3491J279D01*
G01X1688433Y167503D01*
X1688403Y167431D01*
Y167069D01*
X1688433Y166997D01*
X1688461Y166968D01*
G02X1689357Y165415I-2485J-2469D01*
G03X1689472Y165283I193J52D01*
G02X1691602Y162060I-1372J-3222D01*
G02X1689582Y158887I-3502J0D01*
G03X1689467Y158721I85J-181D01*
G02X1688461Y156532I-3491J279D01*
G01X1688433Y156503D01*
X1688403Y156431D01*
Y156069D01*
X1688433Y155997D01*
X1688461Y155968D01*
G02Y151032I-2486J-2468D01*
G01X1688433Y151003D01*
X1688403Y150931D01*
Y150569D01*
X1688433Y150497D01*
X1688461Y150468D01*
G02X1689357Y148915I-2485J-2469D01*
G03X1689472Y148783I193J52D01*
G02X1691602Y145560I-1372J-3222D01*
G02X1688100Y142058I-3502J0D01*
G02X1684719Y144645I0J3503D01*
G03X1684604Y144777I-193J-52D01*
G02X1682474Y148000I1372J3222D01*
G02X1683491Y150468I3503J0D01*
G01X1683519Y150497D01*
X1683549Y150569D01*
Y150931D01*
X1683519Y151003D01*
X1683491Y151032D01*
G02X1682474Y153500I2486J2468D01*
G01Y153525D01*
G03X1682393Y153687I-200J1D01*
G02X1682361Y153711I2084J2812D01*
G03X1682119I-121J-159D01*
G02X1680000Y152998I-2118J2789D01*
G02X1676498Y156467I0J3502D01*
G03X1676441Y156605I-200J-2D01*
G01X1676357Y156690D01*
G03X1676221Y156751I-144J-139D01*
G02X1672848Y160251I129J3500D01*
G02X1676350Y163754I3502J1D01*
G02X1679852Y160284I0J-3502D01*
G03X1679909Y160146I200J2D01*
G01X1679993Y160061D01*
G03X1680129Y160000I144J139D01*
G02X1682119Y159289I-129J-3500D01*
G03X1682361I121J159D01*
G02X1682424Y159336I2124J-2782D01*
G03X1682505Y159471I-117J162D01*
G02X1683491Y161468I3471J-472D01*
G01X1683519Y161497D01*
X1683549Y161569D01*
Y161931D01*
X1683519Y162003D01*
X1683491Y162032D01*
G02Y166968I2486J2468D01*
G01X1683519Y166997D01*
X1683549Y167069D01*
Y167431D01*
X1683519Y167503D01*
X1683491Y167532D01*
G02Y172468I2486J2468D01*
G01X1683519Y172497D01*
X1683549Y172569D01*
Y172931D01*
X1683519Y173003D01*
X1683491Y173032D01*
G02Y177968I2486J2468D01*
G01X1683519Y177997D01*
X1683549Y178069D01*
Y178431D01*
X1683519Y178503D01*
X1683491Y178532D01*
G02X1682474Y181000I2486J2468D01*
G02X1683490Y183468I3503J1D01*
G01X1683519Y183496D01*
X1683549Y183568D01*
G37*
G36*
G01X1719705Y201505D02*
X1719698Y201938D01*
X1719649Y202026D01*
X1719607Y202053D01*
G02X1717998Y205000I1894J2947D01*
G02X1721500Y208502I3502J0D01*
G02X1722813Y208247I1J-3502D01*
G03X1722993Y208262I75J185D01*
G02X1724824Y208778I1830J-2986D01*
G02Y201774I0J-3502D01*
G02X1723511Y202029I-1J3502D01*
G03X1723331Y202014I-75J-185D01*
G02X1723322Y202009I-1704J3057D01*
G03X1723226Y201835I104J-171D01*
G01X1723228Y201717D01*
G03X1723329Y201546I200J3D01*
G02X1725102Y198500I-1730J-3046D01*
G02X1724623Y196731I-3502J-1D01*
G03Y196529I173J-101D01*
G02X1725102Y194760I-3023J-1768D01*
G02X1718098I-3502J0D01*
G02X1718577Y196529I3502J1D01*
G03Y196731I-173J101D01*
G02X1718098Y198500I3023J1768D01*
G02X1719617Y201387I3503J0D01*
G01X1719658Y201416D01*
X1719705Y201505D01*
G37*
G36*
G01X1705684Y204830D02*
G02X1708102Y201500I-1084J-3330D01*
G02X1701098I-3502J0D01*
G02X1701127Y201954I3502J4D01*
G03X1700991Y202170I-198J26D01*
G02X1698572Y205500I1083J3331D01*
G02X1705578I3503J0D01*
G02X1705548Y205046I-3503J3D01*
G03X1705684Y204830I198J-26D01*
G37*
G36*
G01X1708618Y189544D02*
G02X1711025Y190502I2407J-2545D01*
G02X1712515Y190170I2J-3502D01*
G03X1712685I85J181D01*
G02X1714175Y190502I1488J-3170D01*
G02Y183498I0J-3502D01*
G02X1712685Y183830I-2J3502D01*
G03X1712515I-85J-181D01*
G02X1711025Y183498I-1488J3170D01*
G02X1709246Y183983I-1J3502D01*
G03X1709007Y183956I-102J-172D01*
G02X1706600Y182998I-2407J2545D01*
G02X1705049Y183360I0J3502D01*
G01X1704995Y183386D01*
X1704880Y183373D01*
X1704506Y183067D01*
X1704470Y182956D01*
X1704485Y182898D01*
G02X1704602Y182000I-3385J-898D01*
G02X1704187Y180345I-3502J-1D01*
G03Y180155I176J-95D01*
G02X1704602Y178500I-3087J-1654D01*
G02X1703137Y175651I-3503J0D01*
G01X1703088Y175616D01*
X1703046Y175505D01*
X1703148Y175029D01*
X1703232Y174946D01*
X1703291Y174934D01*
G02X1706102Y171500I-692J-3434D01*
G02X1703220Y168053I-3502J0D01*
G01X1703161Y168042D01*
X1703074Y167959D01*
X1702965Y167483D01*
X1703007Y167371D01*
X1703056Y167335D01*
G02X1704502Y164500I-2056J-2835D01*
G02X1703485Y162032I-3503J0D01*
G01X1703457Y162003D01*
X1703427Y161931D01*
Y161569D01*
X1703457Y161497D01*
X1703485Y161468D01*
G02X1704502Y159000I-2486J-2468D01*
G02X1701467Y155529I-3502J0D01*
G01X1701420Y155522D01*
X1701342Y155469D01*
X1701141Y155103D01*
X1701137Y155009D01*
X1701157Y154965D01*
G02X1701478Y153500I-3181J-1465D01*
G02X1700461Y151032I-3503J0D01*
G01X1700433Y151003D01*
X1700403Y150931D01*
Y150569D01*
X1700433Y150497D01*
X1700461Y150468D01*
G02X1701478Y148000I-2486J-2468D01*
G02X1694474I-3502J0D01*
G02X1695491Y150468I3503J0D01*
G01X1695519Y150497D01*
X1695549Y150569D01*
Y150931D01*
X1695519Y151003D01*
X1695491Y151032D01*
G02Y155968I2486J2468D01*
G01X1695519Y155997D01*
X1695549Y156069D01*
Y156431D01*
X1695519Y156503D01*
X1695491Y156532D01*
G02Y161468I2486J2468D01*
G01X1695519Y161497D01*
X1695549Y161569D01*
Y161931D01*
X1695519Y162003D01*
X1695491Y162032D01*
G02Y166968I2486J2468D01*
G01X1695519Y166997D01*
X1695549Y167069D01*
Y167431D01*
X1695519Y167503D01*
X1695491Y167532D01*
G02Y172468I2486J2468D01*
G01X1695519Y172497D01*
X1695549Y172569D01*
Y172931D01*
X1695519Y173003D01*
X1695491Y173032D01*
G02X1694474Y175500I2486J2468D01*
G02X1695490Y177968I3503J1D01*
G01X1695519Y177996D01*
X1695549Y178068D01*
X1695548Y178431D01*
X1695519Y178503D01*
X1695490Y178531D01*
G02X1694472Y181000I2485J2469D01*
G02X1697975Y184502I3503J-1D01*
G02X1698496Y184464I6J-3502D01*
G03X1698665Y184518I30J197D01*
G02X1701100Y185502I2434J-2518D01*
G02X1702651Y185140I0J-3502D01*
G01X1702705Y185114D01*
X1702820Y185127D01*
X1703194Y185433D01*
X1703230Y185544D01*
X1703215Y185602D01*
G02X1703098Y186500I3385J898D01*
G02X1706600Y190002I3502J0D01*
G02X1708379Y189517I1J-3502D01*
G03X1708618Y189544I102J172D01*
G37*
G36*
G01X695332Y327292D02*
G02X696610Y327534I1279J-3260D01*
G01X696613D01*
G02Y320530I0J-3502D01*
G01X696610D01*
G02X695332Y320772I1J3502D01*
G03X695185I-73J-186D01*
G02X693907Y320530I-1279J3260D01*
G01X693904D01*
G02Y327534I0J3502D01*
G01X693907D01*
G02X695185Y327292I-1J-3502D01*
G03X695332I73J186D01*
G37*
G36*
G01X1197534Y318912D02*
Y318914D01*
G02X1201037Y315410I3503J-1D01*
G01X1200968D01*
X1200964D01*
X1200920Y315411D01*
X1200838Y315374D01*
X1200608Y315101D01*
G03X1200565Y314934I153J-129D01*
G02X1200630Y314264I-3438J-672D01*
G01Y314262D01*
G02X1197127Y317766I-3503J1D01*
G01X1197196D01*
X1197200D01*
X1197244Y317765D01*
X1197326Y317802D01*
X1197556Y318075D01*
G03X1197599Y318242I-153J129D01*
G02X1197534Y318912I3438J672D01*
G37*
G36*
G01X1176200Y312998D02*
X1176198D01*
G02X1174781Y313298I1J3502D01*
G03X1174619I-81J-183D01*
G02X1173202Y312998I-1418J3202D01*
G01X1173200D01*
G02Y320002I0J3502D01*
G01X1173202D01*
G02X1174619Y319702I-1J-3502D01*
G03X1174781I81J183D01*
G02X1176198Y320002I1418J-3202D01*
G01X1176200D01*
G02Y312998I0J-3502D01*
G37*
G36*
G01X1106661Y304198D02*
X1106659D01*
G02X1105242Y304498I1J3502D01*
G03X1105080I-81J-183D01*
G02X1103663Y304198I-1418J3202D01*
G01X1103661D01*
G02Y311202I0J3502D01*
G01X1103663D01*
G02X1105080Y310902I-1J-3502D01*
G03X1105242I81J183D01*
G02X1106659Y311202I1418J-3202D01*
G01X1106661D01*
G02Y304198I0J-3502D01*
G37*
G36*
G01X565091Y299090D02*
G02Y306094I0J3502D01*
G02X567440Y305189I0J-3501D01*
G01X567469Y305163D01*
X567539Y305137D01*
X567854Y305143D01*
G03X567988Y305199I-5J200D01*
G01X567989Y305200D01*
G02X570443Y306204I2454J-2497D01*
G02Y299200I0J-3502D01*
G02X568094Y300105I0J3501D01*
G01X568065Y300131D01*
X567995Y300157D01*
X567680Y300151D01*
G03X567546Y300095I5J-200D01*
G01X567545Y300094D01*
G02X565091Y299090I-2454J2497D01*
G37*
G36*
G01X1199059Y290701D02*
X1198941D01*
G03X1198810Y290651I1J-200D01*
G02X1196500Y289782I-2309J2634D01*
G02Y296786I0J3502D01*
G02X1198810Y295917I1J-3503D01*
G03X1198941Y295867I132J150D01*
G01X1199059D01*
G03X1199190Y295917I-1J200D01*
G02X1201500Y296786I2309J-2634D01*
G02Y289782I0J-3502D01*
G02X1199190Y290651I-1J3503D01*
G03X1199059Y290701I-132J-150D01*
G37*
G36*
G01X568040Y289065D02*
G02X568411Y290634I3502J0D01*
G03X568399Y290833I-179J89D01*
G02X567823Y292757I2926J1924D01*
G02X574827I3502J0D01*
G02X574456Y291188I-3502J0D01*
G03X574468Y290989I179J-89D01*
G02X575044Y289065I-2926J-1924D01*
G02X568040I-3502J0D01*
G37*
G36*
G01X1055300Y287398D02*
X1055297D01*
G02X1053834Y287719I2J3502D01*
G03X1053666I-84J-182D01*
G02X1052203Y287398I-1465J3181D01*
G01X1052200D01*
G02Y294402I0J3502D01*
G01X1052203D01*
G02X1053666Y294081I-2J-3502D01*
G03X1053834I84J182D01*
G02X1055297Y294402I1465J-3181D01*
G01X1055300D01*
G02Y287398I0J-3502D01*
G37*
G36*
G01X1059300Y276098D02*
X1059298D01*
G02X1057550Y276566I1J3502D01*
G03X1057350I-100J-173D01*
G02X1055602Y276098I-1749J3034D01*
G01X1055600D01*
G02Y283102I0J3502D01*
G01X1055602D01*
G02X1057350Y282634I-1J-3502D01*
G03X1057550I100J173D01*
G02X1059298Y283102I1749J-3034D01*
G01X1059300D01*
G02Y276098I0J-3502D01*
G37*
G36*
G01X715982Y278980D02*
G02X722986I3502J0D01*
G02X720657Y275680I-3502J0D01*
G01X720615Y275665D01*
X720553Y275604D01*
X720430Y275276D01*
G03X720442Y275108I187J-71D01*
G02X720886Y273403I-3058J-1707D01*
G01Y273400D01*
G02X713882I-3502J0D01*
G02X716211Y276700I3502J0D01*
G01X716253Y276715D01*
X716315Y276776D01*
X716438Y277104D01*
G03X716426Y277272I-187J71D01*
G02X715982Y278977I3058J1707D01*
G01Y278980D01*
G37*
G36*
G01X706684Y268898D02*
X706682D01*
G02X704934Y269366I1J3502D01*
G03X704734I-100J-173D01*
G02X702986Y268898I-1749J3034D01*
G01X702984D01*
G02Y275902I0J3502D01*
G01X702986D01*
G02X704734Y275434I-1J-3502D01*
G03X704934I100J173D01*
G02X706682Y275902I1749J-3034D01*
G01X706684D01*
G02Y268898I0J-3502D01*
G37*
G36*
G01X730600Y266498D02*
X730598D01*
G02X729181Y266798I1J3502D01*
G03X729019I-81J-183D01*
G02X727602Y266498I-1418J3202D01*
G01X727600D01*
G02Y273502I0J3502D01*
G01X727602D01*
G02X729019Y273202I-1J-3502D01*
G03X729181I81J183D01*
G02X730598Y273502I1418J-3202D01*
G01X730600D01*
G02Y266498I0J-3502D01*
G37*
G36*
G01X1059300Y264998D02*
X1059298D01*
G02X1057550Y265466I1J3502D01*
G03X1057350I-100J-173D01*
G02X1055602Y264998I-1749J3034D01*
G01X1055600D01*
G02Y272002I0J3502D01*
G01X1055602D01*
G02X1057350Y271534I-1J-3502D01*
G03X1057550I100J173D01*
G02X1059298Y272002I1749J-3034D01*
G01X1059300D01*
G02Y264998I0J-3502D01*
G37*
G36*
G01X710084Y257598D02*
X710081D01*
G02X708618Y257919I2J3502D01*
G03X708450I-84J-182D01*
G02X706987Y257598I-1465J3181D01*
G01X706984D01*
G02Y264602I0J3502D01*
G01X706987D01*
G02X708450Y264281I-2J-3502D01*
G03X708618I84J182D01*
G02X710081Y264602I1465J-3181D01*
G01X710084D01*
G02Y257598I0J-3502D01*
G37*
G36*
G01X658600Y234198D02*
X658598D01*
G02X657181Y234498I1J3502D01*
G03X657019I-81J-183D01*
G02X655602Y234198I-1418J3202D01*
G01X655600D01*
G02Y241202I0J3502D01*
G01X655602D01*
G02X657019Y240902I-1J-3502D01*
G03X657181I81J183D01*
G02X658598Y241202I1418J-3202D01*
G01X658600D01*
G02Y234198I0J-3502D01*
G37*
G36*
G01X1070600Y231502D02*
G02X1072019Y231202I1J-3502D01*
G03X1072181I81J183D01*
G02X1073598Y231502I1418J-3202D01*
G01X1073600D01*
G02Y224498I0J-3502D01*
G01X1073598D01*
G02X1072181Y224798I1J3502D01*
G03X1072019I-81J-183D01*
G02X1070600Y224498I-1418J3202D01*
G02X1067907Y225760I-1J3502D01*
G01X1067879Y225794D01*
X1067799Y225832D01*
X1067401D01*
X1067321Y225794D01*
X1067293Y225760D01*
G02X1064600Y224498I-2692J2240D01*
G02X1063181Y224798I-1J3502D01*
G03X1063019I-81J-183D01*
G02X1061602Y224498I-1418J3202D01*
G01X1061600D01*
G02Y231502I0J3502D01*
G01X1061602D01*
G02X1063019Y231202I-1J-3502D01*
G03X1063181I81J183D01*
G02X1064600Y231502I1418J-3202D01*
G02X1067293Y230240I1J-3502D01*
G01X1067321Y230206D01*
X1067401Y230168D01*
X1067799D01*
X1067879Y230206D01*
X1067907Y230240D01*
G02X1070600Y231502I2692J-2240D01*
G37*
G36*
G01X704934Y286534D02*
G02X706684Y287002I1749J-3034D01*
G02Y279998I0J-3502D01*
G02X704934Y280466I-1J3502D01*
G03X704734I-100J-173D01*
G02X702984Y279998I-1749J3034D01*
G02Y287002I0J3502D01*
G02X704734Y286534I1J-3502D01*
G03X704934I100J173D01*
G37*
G36*
G01X592781Y243211D02*
G02X593708Y243336I927J-3378D01*
G02X594718Y243187I-1J-3503D01*
G03X594803Y243180I59J191D01*
G02X595276Y243212I472J-3470D01*
G02X595658Y243191I-1J-3502D01*
G03X595735Y243198I21J199D01*
G02X596708Y243336I974J-3365D01*
G02Y236330I0J-3503D01*
G02X596323Y236352I7J3503D01*
G03X596246Y236345I-21J-199D01*
G02X595276Y236208I-970J3365D01*
G02X594268Y236356I-1J3502D01*
G03X594183Y236363I-59J-191D01*
G02X593708Y236330I-480J3470D01*
G02X593467Y236339I10J3503D01*
G03X593400Y236332I-13J-200D01*
G02X592476Y236208I-924J3378D01*
G02Y243212I0J3502D01*
G02X592714Y243204I1J-3502D01*
G03X592781Y243211I13J199D01*
G37*
G36*
G01X1527504Y664685D02*
G02X1532283Y669464I4779J0D01*
G02X1535916Y667789I-1J-4779D01*
G03X1536068Y667719I152J130D01*
G01X1536372D01*
G03X1536524Y667789I0J200D01*
G02X1540157Y669464I3634J-3104D01*
G02X1544936Y664685I0J-4779D01*
G02X1543261Y661052I-4779J1D01*
G03X1543191Y660900I130J-152D01*
G01Y660596D01*
G03X1543261Y660444I200J0D01*
G02X1544936Y656811I-3104J-3634D01*
G02X1543261Y653178I-4779J1D01*
G03X1543191Y653026I130J-152D01*
G01Y652722D01*
G03X1543261Y652570I200J0D01*
G02X1544936Y648937I-3104J-3634D01*
G02X1540157Y644158I-4779J0D01*
G02X1536524Y645833I1J4779D01*
G03X1536372Y645903I-152J-130D01*
G01X1536068D01*
G03X1535916Y645833I0J-200D01*
G02X1532283Y644158I-3634J3104D01*
G02X1527504Y648937I0J4779D01*
G02X1529179Y652570I4779J-1D01*
G03X1529249Y652722I-130J152D01*
G01Y653026D01*
G03X1529179Y653178I-200J0D01*
G02X1527504Y656811I3104J3634D01*
G02X1529179Y660444I4779J-1D01*
G03X1529249Y660596I-130J152D01*
G01Y660900D01*
G03X1529179Y661052I-200J0D01*
G02X1527504Y664685I3104J3634D01*
G37*
G54D57*
X396216Y46875D03*
X134600Y150000D03*
X430608Y211389D03*
X408100Y224500D03*
Y180100D03*
X428277Y167056D03*
X1769425Y203000D03*
X1652600Y212000D03*
X1809600Y195000D03*
X1800100Y187500D03*
X1778000Y189500D03*
X1754260Y187260D03*
X1729411Y143661D03*
X332500Y63300D03*
X1551000Y96500D03*
X1567500Y67000D03*
X1594930Y115000D03*
X1706100Y92000D03*
X1727200Y104500D03*
X1597100Y126000D03*
X1649197Y132915D03*
X1638707Y132954D03*
X1667000Y138000D03*
X1658500D03*
X1692600Y135975D03*
X1702525Y129500D03*
X1738000Y124500D03*
X1597100Y145000D03*
X1636600Y173500D03*
X1635000Y152925D03*
X1624000Y189000D03*
X1631585Y188777D03*
X1658000Y179500D03*
X1668075Y189500D03*
X1672050Y181550D03*
X1731925Y199000D03*
X1729000Y183500D03*
X1715525Y168500D03*
X1679176Y194760D03*
X506309Y329000D03*
X517410D03*
X725000Y292500D03*
X623500Y379000D03*
X1173500Y298500D03*
X704240Y185000D03*
X632186Y338917D03*
X1034360Y254000D03*
X1034537Y201437D03*
X1355100Y160000D03*
X1334140Y146642D03*
X1355000Y204400D03*
X1332671Y190644D03*
G54D59*
X243785Y550000D03*
Y470000D03*
Y390000D03*
Y310000D03*
Y230000D03*
X166785Y550000D03*
Y470000D03*
Y390000D03*
Y310000D03*
Y230000D03*
X1488500Y310000D03*
Y230000D03*
Y390000D03*
X1565500D03*
X1488500Y550000D03*
X1565500D03*
X1488500Y470000D03*
X1565500D03*
Y310000D03*
Y230000D03*
G54D60*
X1451417Y20827D03*
X260866D03*
G54D64*
X940197Y200984D03*
X822087D03*
G54D58*
X243785Y200472D03*
X166785D03*
X243785Y520472D03*
Y440472D03*
Y360472D03*
Y280472D03*
X166785Y520472D03*
Y440472D03*
Y360472D03*
Y280472D03*
X1488500Y200472D03*
Y280472D03*
Y360472D03*
Y440472D03*
Y520472D03*
X1565500Y200472D03*
Y280472D03*
Y360472D03*
Y440472D03*
Y520472D03*
G54D62*
X1529100Y78500D03*
G54D55*
X207874Y639094D03*
X1524409D03*
G54D65*
X1856772Y360433D03*
X1851457Y220433D03*
G54D56*
X393703Y354332D03*
X314961Y570866D03*
X279529Y62992D03*
X1452757Y62992D03*
X1338585Y354332D03*
X1417325Y570866D03*
G54D54*
X287402Y628465D03*
X1468504D03*
G54D53*
X19685Y766166D03*
X1854331D03*
X1212478Y300181D03*
G54D63*
X940197Y313484D03*
X822087Y88484D03*
Y313484D03*
X940197Y88484D03*
G54D61*
X1673228Y236614D03*
G54D52*
X59055Y411594D03*
Y236614D03*
X1673228Y411614D03*
G36*
G01X269508Y66522D02*
G02X289549Y66521I10021J6311D01*
G03X287434Y59195I11632J-7326D01*
G01Y53148D01*
G02X271622I-7906J0D01*
G01Y59195D01*
G03X269508Y66522I-13749J2D01*
G37*
G36*
G01X304941Y574397D02*
G02X324982Y574396I10021J6311D01*
G03X322867Y567070I11632J-7326D01*
G01Y561023D01*
G02X307055I-7906J0D01*
G01Y567070D01*
G03X304941Y574397I-13749J2D01*
G37*
G36*
G01X383682Y357862D02*
G02X403723Y357861I10021J6311D01*
G03X401608Y350535I11632J-7326D01*
G01Y344488D01*
G02X385796I-7906J0D01*
G01Y350535D01*
G03X383682Y357862I-13749J2D01*
G37*
G36*
G01X1328564D02*
G02X1348605Y357861I10021J6311D01*
G03X1346490Y350535I11632J-7326D01*
G01Y344488D01*
G02X1330678I-7906J0D01*
G01Y350535D01*
G03X1328564Y357862I-13749J2D01*
G37*
G36*
G01X1407304Y574397D02*
G02X1427345Y574396I10021J6311D01*
G03X1425230Y567070I11632J-7326D01*
G01Y561023D01*
G02X1409418I-7906J0D01*
G01Y567070D01*
G03X1407304Y574397I-13749J2D01*
G37*
G36*
G01X1442736Y66523D02*
G02X1462777Y66522I10021J6311D01*
G03X1460662Y59196I11632J-7326D01*
G01Y53149D01*
G02X1444850I-7906J0D01*
G01Y59196D01*
G03X1442736Y66523I-13749J2D01*
G37*
G36*
G01X41338Y17716D02*
G03X53150I5906J0D01*
G01Y23763D01*
G02X55572Y32155I15747J1D01*
G03X38916I-8328J5246D01*
G02X41338Y23763I-13327J-8392D01*
G01Y17716D01*
G37*
G36*
G01Y330708D02*
G03X53150I5906J0D01*
G01Y336755D01*
G02X55572Y345147I15747J1D01*
G03X38916I-8328J5246D01*
G02X41338Y336755I-13327J-8392D01*
G01Y330708D01*
G37*
G36*
G01X273622Y53148D02*
G03X285434I5906J0D01*
G01Y59195D01*
G02X287856Y67587I15747J1D01*
G03X271200I-8328J5246D01*
G02X273622Y59195I-13327J-8392D01*
G01Y53148D01*
G37*
G36*
G01X309055Y561023D02*
G03X320867I5906J0D01*
G01Y567070D01*
G02X323289Y575462I15747J1D01*
G03X306633I-8328J5246D01*
G02X309055Y567070I-13327J-8392D01*
G01Y561023D01*
G37*
G36*
G01X387796Y344488D02*
G03X399608I5906J0D01*
G01Y350535D01*
G02X402030Y358927I15747J1D01*
G03X385374I-8328J5246D01*
G02X387796Y350535I-13327J-8392D01*
G01Y344488D01*
G37*
G36*
G01X742126Y64961D02*
G03X753938I5906J0D01*
G01Y71008D01*
G02X756360Y79400I15747J1D01*
G03X739704I-8328J5246D01*
G02X742126Y71008I-13327J-8392D01*
G01Y64961D01*
G37*
G36*
G01Y344488D02*
G03X753938I5906J0D01*
G01Y350535D01*
G02X756360Y358927I15747J1D01*
G03X739704I-8328J5246D01*
G02X742126Y350535I-13327J-8392D01*
G01Y344488D01*
G37*
G36*
G01X978346Y64961D02*
G03X990158I5906J0D01*
G01Y71008D01*
G02X992580Y79400I15747J1D01*
G03X975924I-8328J5246D01*
G02X978346Y71008I-13327J-8392D01*
G01Y64961D01*
G37*
G36*
G01Y344488D02*
G03X990158I5906J0D01*
G01Y350535D01*
G02X992580Y358927I15747J1D01*
G03X975924I-8328J5246D01*
G02X978346Y350535I-13327J-8392D01*
G01Y344488D01*
G37*
G36*
G01X1332678D02*
G03X1344490I5906J0D01*
G01Y350535D01*
G02X1346912Y358927I15747J1D01*
G03X1330256I-8328J5246D01*
G02X1332678Y350535I-13327J-8392D01*
G01Y344488D01*
G37*
G36*
G01X1411418Y561023D02*
G03X1423230I5906J0D01*
G01Y567070D01*
G02X1425652Y575462I15747J1D01*
G03X1408996I-8328J5246D01*
G02X1411418Y567070I-13327J-8392D01*
G01Y561023D01*
G37*
G36*
G01X1446850Y53149D02*
G03X1458662I5906J0D01*
G01Y59196D01*
G02X1461084Y67588I15747J1D01*
G03X1444428I-8328J5246D01*
G02X1446850Y59196I-13327J-8392D01*
G01Y53149D01*
G37*
G36*
G01X1679134Y17716D02*
G03X1690946I5906J0D01*
G01Y23763D01*
G02X1693368Y32155I15747J1D01*
G03X1676712I-8328J5246D01*
G02X1679134Y23763I-13327J-8392D01*
G01Y17716D01*
G37*
G36*
G01Y330708D02*
G03X1690946I5906J0D01*
G01Y336755D01*
G02X1693368Y345147I15747J1D01*
G03X1676712I-8328J5246D01*
G02X1679134Y336755I-13327J-8392D01*
G01Y330708D01*
G37*
G36*
G01X1793306Y96457D02*
G03X1805118I5906J0D01*
G01Y102504D01*
G02X1807540Y110896I15747J1D01*
G03X1790884I-8328J5246D01*
G02X1793306Y102504I-13327J-8392D01*
G01Y96457D01*
G37*
G36*
G01Y478346D02*
G03X1805118I5906J0D01*
G01Y484393D01*
G02X1807540Y492785I15747J1D01*
G03X1790884I-8328J5246D01*
G02X1793306Y484393I-13327J-8392D01*
G01Y478346D01*
G37*
G54D11*
X3018Y23930D03*
X10493Y5830D03*
X3018Y43930D03*
Y83930D03*
Y63930D03*
Y103930D03*
Y143930D03*
Y123930D03*
Y163930D03*
Y203930D03*
Y183930D03*
Y223930D03*
Y263930D03*
Y243930D03*
Y283930D03*
Y323930D03*
Y303930D03*
Y343930D03*
Y383930D03*
Y363930D03*
Y403930D03*
Y443930D03*
Y423930D03*
Y463930D03*
Y503930D03*
Y483930D03*
Y523930D03*
Y563930D03*
Y543930D03*
Y583930D03*
X15642Y619715D03*
X3018Y603930D03*
X30709Y3014D03*
X35455Y620194D03*
X75455D03*
X55455D03*
X81406Y3042D03*
X101406D03*
X95455Y620194D03*
X121406Y3042D03*
X134600Y150000D03*
Y134000D03*
X114923Y623982D03*
X124901Y640105D03*
X161406Y3042D03*
X141406D03*
X156785Y101285D03*
X154778Y672779D03*
X181406Y3042D03*
X187600Y106500D03*
X176785Y102000D03*
X194778Y672779D03*
X174778D03*
X201406Y3042D03*
X221406D03*
X211425Y106075D03*
X210925Y115575D03*
X214778Y672779D03*
X229829Y103412D03*
X233329D03*
X237329D03*
X229829Y99503D03*
X233329D03*
X237329D03*
X229953Y95780D03*
X233453D03*
X237453D03*
X229891Y92305D03*
X233391D03*
X237391D03*
X254778Y672779D03*
X234778D03*
X274778D03*
X317000Y58000D03*
X314766Y39211D03*
X317766D03*
X317000Y74475D03*
Y64500D03*
X311956Y651522D03*
X294778Y672779D03*
X323766Y39211D03*
X320766D03*
X321500Y74475D03*
Y66500D03*
X325100Y64000D03*
X332500Y63300D03*
X330500Y74476D03*
X324000Y77000D03*
X321000Y63000D03*
X326000Y74476D03*
X345412Y435017D03*
Y455017D03*
Y475017D03*
Y495017D03*
Y515017D03*
Y535017D03*
Y555017D03*
Y575017D03*
Y595017D03*
X342119Y613510D03*
X331285Y620008D03*
X369192Y38417D03*
X372192D03*
X378192D03*
X375192D03*
X362127Y406608D03*
X350024Y418335D03*
X396216Y46875D03*
X408100Y180100D03*
Y224500D03*
X399680Y402510D03*
X379680D03*
X428277Y167056D03*
X438100Y170000D03*
X430608Y211389D03*
X438100Y214500D03*
X419680Y402510D03*
X468946Y338216D03*
X465946D03*
X468946Y341216D03*
X465946D03*
X458946Y338216D03*
X455946D03*
X458946Y341216D03*
X455946D03*
X459680Y402510D03*
X439680D03*
X471946Y338216D03*
Y341216D03*
X481446Y338216D03*
X478446D03*
X481446Y341216D03*
X478446D03*
X484446Y338216D03*
Y341216D03*
X479680Y402510D03*
X517409Y322000D03*
X506309Y329000D03*
Y322000D03*
X517410Y329000D03*
X499680Y402510D03*
X519680D03*
X551430Y132400D03*
X561155Y160784D03*
X551430Y265600D03*
X539680Y402510D03*
X559680D03*
X563007Y118477D03*
Y114123D03*
X562830Y133300D03*
Y136800D03*
Y140300D03*
Y143800D03*
X574230Y132400D03*
X564305Y160784D03*
X563007Y251677D03*
X576467Y265600D03*
X563007Y247323D03*
X562830Y270000D03*
Y266500D03*
X590298Y282890D03*
X562830Y277000D03*
X571325Y292757D03*
X590298Y276984D03*
X562830Y273500D03*
X571542Y289065D03*
X565091Y302592D03*
X570443Y302702D03*
X579680Y402510D03*
X595276Y239710D03*
X592476D03*
X620600Y239161D03*
X605800Y256500D03*
X609637Y254523D03*
X605700Y259500D03*
X616184Y267000D03*
X604684D03*
X612684Y297000D03*
X616684Y294500D03*
X602928Y293969D03*
X606084Y293100D03*
X600875Y295937D03*
X616184Y276000D03*
X604684D03*
Y285000D03*
X616184D03*
X601675Y305575D03*
X616684Y307975D03*
X622184Y308000D03*
X608259Y305000D03*
X618500Y333500D03*
X619680Y402510D03*
X599680D03*
X639010Y236377D03*
X640684Y264500D03*
Y269000D03*
X645900Y242200D03*
X644502Y246839D03*
X649200Y254500D03*
X650100Y251500D03*
X623684Y281000D03*
X637684Y280575D03*
X629018Y277500D03*
X625684Y273499D03*
X630308Y284500D03*
X632186Y338917D03*
X623500Y379000D03*
X639680Y402510D03*
X676638Y230894D03*
X658600Y237700D03*
X655600D03*
X681684Y230820D03*
X657259Y263000D03*
X674800Y269600D03*
X660684Y262500D03*
X654100Y263000D03*
X651100Y266000D03*
X679184Y278980D03*
X673684Y280950D03*
X676684D03*
X670184Y288500D03*
X662184Y280500D03*
Y288500D03*
Y284500D03*
X679184Y273190D03*
X676184Y274000D03*
X657500Y330075D03*
X662075Y320000D03*
X675100Y304500D03*
X662125Y308500D03*
X662100Y304500D03*
X658925Y320000D03*
X659680Y402510D03*
X679680D03*
X702223Y197419D03*
X704240Y185000D03*
X689684Y230762D03*
X683592Y259908D03*
X688945Y259761D03*
X695259Y248020D03*
X706984Y261100D03*
X710084D03*
X691794Y261073D03*
X692109Y248020D03*
X686784Y268100D03*
X695584D03*
X698433Y247119D03*
X685884Y297000D03*
X702984Y283500D03*
X706684D03*
X702984Y272400D03*
X706684D03*
X686784Y278000D03*
X695584D03*
X686784Y287900D03*
X695684D03*
X710900Y324100D03*
X696613Y324032D03*
X693904D03*
X691759Y309000D03*
X699680Y402510D03*
X712000Y215500D03*
X730600Y270000D03*
X727600D03*
X717384Y273400D03*
X719484Y278980D03*
X725000Y292500D03*
X722925Y299500D03*
X719433Y328087D03*
X734500Y307425D03*
X717401Y329996D03*
X739680Y402510D03*
X719680D03*
X770700Y206900D03*
X759680Y402510D03*
X776000Y206600D03*
X779680Y402510D03*
X799680D03*
X819680D03*
X862600Y29500D03*
X839680Y402510D03*
X859680D03*
X867100Y28000D03*
X872533Y29432D03*
X867100Y31500D03*
X887500Y355680D03*
X885100Y361500D03*
X885265Y381000D03*
X878175Y374100D03*
Y364709D03*
X879680Y402510D03*
X919680D03*
X899680D03*
X894500Y396500D03*
X954200Y200200D03*
X954600Y207200D03*
X939680Y402510D03*
X978600Y310955D03*
X959680Y402510D03*
X979680D03*
X999680D03*
X1030100Y207500D03*
X1034537Y201437D03*
X1024600Y185000D03*
X1027675Y215000D03*
X1024525D03*
X1034360Y254000D03*
X1032500Y281800D03*
X1029500D03*
X1044900Y278600D03*
X1042800Y273020D03*
X1017300Y322500D03*
X1026270Y303729D03*
X1023492Y346593D03*
X1021414Y355979D03*
X1017300Y385600D03*
X1039680Y402510D03*
X1019680D03*
X1047163Y197437D03*
X1061600Y228000D03*
X1064600D03*
X1073600D03*
X1070600D03*
X1066600Y264100D03*
X1074430Y256461D03*
X1059300Y268500D03*
X1055600D03*
X1070525Y243000D03*
X1066700Y274000D03*
Y283900D03*
X1052200Y290900D03*
X1055300D03*
X1070490Y290927D03*
X1055600Y279600D03*
X1059300D03*
X1073339Y292239D03*
X1062600Y305000D03*
X1070175Y303980D03*
X1067025D03*
X1072600Y324000D03*
X1064600D03*
X1059680Y402510D03*
X1092100Y263500D03*
X1100100Y243500D03*
X1100500Y263500D03*
X1100100Y247500D03*
X1075500Y264100D03*
X1085600Y271050D03*
X1101500Y271500D03*
X1083100Y273020D03*
X1088079Y274980D03*
X1087100Y282500D03*
X1101600Y289500D03*
X1080600Y294000D03*
X1075500Y274000D03*
Y283900D03*
X1102600Y296000D03*
X1083100Y278810D03*
X1086100Y278000D03*
X1103661Y307700D03*
X1080600Y324000D03*
X1094500Y355600D03*
Y360500D03*
X1079680Y402510D03*
X1099680D03*
X1129800Y265400D03*
X1131976Y267500D03*
X1108100Y289000D03*
X1121600Y287500D03*
Y283000D03*
X1105025Y289000D03*
X1111100Y291500D03*
Y285000D03*
X1121100Y296000D03*
X1124600Y271425D03*
X1132113Y274500D03*
X1112000Y296000D03*
X1106661Y307700D03*
X1111100Y300500D03*
X1118000Y303500D03*
X1123100Y322500D03*
Y319500D03*
X1130100Y305174D03*
X1130510Y307720D03*
X1123400Y356300D03*
X1132000Y367000D03*
X1119680Y402510D03*
X1145600Y257500D03*
X1149600Y255000D03*
X1160990Y252134D03*
X1146100Y267000D03*
X1157600D03*
X1156200Y258900D03*
X1145600Y244025D03*
X1140100Y244000D03*
X1154025Y247000D03*
X1163266Y255311D03*
X1156584Y292488D03*
X1156509Y295396D03*
X1157600Y276000D03*
X1146100D03*
Y285000D03*
X1157600D03*
X1136000Y278953D03*
X1157800Y312050D03*
X1157138Y303000D03*
X1141600Y312839D03*
X1141500Y347500D03*
X1138500D03*
X1162425Y340500D03*
X1166000Y352500D03*
X1163000D03*
X1153500Y342500D03*
X1159680Y402510D03*
X1139680D03*
X1187700Y132400D03*
X1197425Y160284D03*
X1187700Y265600D03*
X1171986Y269110D03*
X1173500Y298500D03*
X1196500Y293284D03*
X1171986Y275016D03*
X1176200Y316500D03*
X1173200D03*
X1176000Y350000D03*
X1167800Y355000D03*
X1168200Y349700D03*
X1178900Y359620D03*
X1179500Y350000D03*
Y355000D03*
X1179680Y402510D03*
X1199277Y118477D03*
Y114123D03*
X1210500Y132400D03*
X1199100Y140300D03*
Y133300D03*
Y143800D03*
Y136800D03*
X1200575Y160284D03*
X1199277Y247323D03*
X1210500Y265600D03*
X1199277Y251677D03*
X1199100Y270000D03*
Y266500D03*
X1201500Y293284D03*
X1199100Y277000D03*
Y273500D03*
X1201037Y318912D03*
X1197127Y314264D03*
X1199680Y402510D03*
X1219680D03*
X1244874Y330000D03*
X1255975D03*
Y337000D03*
X1239680Y402510D03*
X1259680D03*
X1279680D03*
X1313366Y38482D03*
X1307366D03*
X1310366D03*
X1299680Y402510D03*
X1316366Y38482D03*
X1334140Y146642D03*
X1324100Y150500D03*
Y194900D03*
X1332671Y190644D03*
X1339680Y402510D03*
X1319680D03*
X1355310Y38893D03*
X1352310D03*
X1349310D03*
X1358310D03*
X1355100Y160000D03*
X1355000Y204400D03*
X1359620Y402940D03*
X1386882Y434539D03*
Y454539D03*
Y474539D03*
Y494539D03*
Y514539D03*
Y534539D03*
Y554539D03*
Y574539D03*
Y594539D03*
X1389643Y612723D03*
X1403035Y620181D03*
X1422310Y40481D03*
X1419310D03*
X1416310D03*
X1425310D03*
X1420335Y635388D03*
Y655388D03*
X1428754Y670547D03*
X1445829Y672778D03*
X1465829D03*
X1498180Y63500D03*
X1494728Y83500D03*
X1490000Y80500D03*
X1499228Y74500D03*
X1490000Y84000D03*
X1494728Y66500D03*
X1490228D03*
X1491918Y107773D03*
Y110773D03*
Y113773D03*
Y104773D03*
X1488918D03*
Y113773D03*
Y110773D03*
Y107773D03*
X1485918Y104773D03*
Y113773D03*
Y110773D03*
Y107773D03*
X1482918Y104773D03*
Y113773D03*
Y110773D03*
Y107773D03*
X1485829Y672778D03*
X1508460Y3003D03*
X1505100Y64500D03*
X1503728Y74477D03*
X1527100Y108500D03*
Y98925D03*
X1524600Y111500D03*
X1505829Y672778D03*
X1525829D03*
X1548460Y3003D03*
X1528460D03*
X1531600Y96941D03*
X1551000Y96500D03*
X1545829Y672778D03*
X1588460Y3003D03*
X1568460D03*
X1567500Y67000D03*
X1565829Y672778D03*
X1585829D03*
X1608460Y3003D03*
X1609100Y85500D03*
Y82000D03*
X1606100Y85500D03*
Y82000D03*
X1609100Y69500D03*
Y66000D03*
Y62500D03*
X1606100Y69500D03*
Y66000D03*
Y62500D03*
X1618800Y76700D03*
X1615800Y82700D03*
Y79700D03*
Y76700D03*
X1602100Y85500D03*
Y82000D03*
Y69500D03*
Y66000D03*
Y62500D03*
X1594930Y115000D03*
X1614100Y110000D03*
Y115000D03*
X1609100Y89000D03*
X1606100D03*
X1602100D03*
X1597100Y145000D03*
Y126000D03*
X1614100Y125000D03*
Y120000D03*
Y130000D03*
X1618100Y148925D03*
X1613527Y627220D03*
X1607226Y650448D03*
X1602599Y667628D03*
X1648460Y3003D03*
X1628460D03*
X1618800Y79700D03*
Y82700D03*
X1647800Y83200D03*
Y77200D03*
Y80200D03*
X1622295Y114940D03*
X1629870Y104240D03*
X1625370Y103940D03*
X1642037Y104134D03*
X1643537Y101434D03*
X1640037D03*
X1638537Y104134D03*
X1645537D03*
X1647037Y101434D03*
X1632336Y109117D03*
X1631323Y115140D03*
X1624500Y142500D03*
Y146000D03*
X1622295Y118940D03*
X1647837Y121812D03*
X1638707Y132954D03*
X1644917Y124581D03*
X1641932Y122969D03*
X1635000Y152925D03*
X1623100Y172500D03*
Y178000D03*
X1650117Y180000D03*
X1636600Y173500D03*
X1622100Y155931D03*
X1626000Y163500D03*
Y167500D03*
X1626925Y156000D03*
X1629000Y175000D03*
X1631585Y188777D03*
X1624000Y189000D03*
X1642000Y184500D03*
X1645000D03*
X1628658Y620261D03*
X1648675Y620226D03*
X1657050Y102380D03*
X1662000Y106000D03*
X1660250Y113860D03*
X1657050Y116760D03*
Y113860D03*
X1660250Y116760D03*
X1669800Y120400D03*
X1675800D03*
X1651037Y99734D03*
X1658500Y138000D03*
X1649197Y132915D03*
X1650990Y122034D03*
X1667000Y138000D03*
X1672800Y120400D03*
X1656657Y127365D03*
X1651325Y125076D03*
X1649500Y173398D03*
X1676350Y160251D03*
X1672050Y181550D03*
X1668075Y189500D03*
X1679176Y194760D03*
X1657500Y191500D03*
X1664000Y202500D03*
X1661500Y199000D03*
X1667600Y198500D03*
X1658000Y179500D03*
X1654000Y192500D03*
X1660000Y193500D03*
X1652600Y212000D03*
X1668675Y620226D03*
X1708460Y3003D03*
X1692000Y76570D03*
X1695500Y76500D03*
X1706100Y92000D03*
X1701350Y114250D03*
X1696600Y119000D03*
X1682500Y121825D03*
X1697976Y148000D03*
X1690100Y127375D03*
X1685100Y127500D03*
X1702525Y129500D03*
X1685976Y148000D03*
X1692600Y135975D03*
X1688100Y145560D03*
X1705100Y140500D03*
X1707100Y142500D03*
X1685000Y133000D03*
X1702600Y171500D03*
X1697976Y164500D03*
Y159000D03*
Y175500D03*
Y170000D03*
Y153500D03*
X1680000Y156500D03*
X1685976Y164500D03*
Y159000D03*
Y153500D03*
Y175500D03*
Y170000D03*
X1701100Y178500D03*
X1688100Y173060D03*
Y162060D03*
X1709600Y158000D03*
X1701000Y159000D03*
Y164500D03*
X1685975Y186500D03*
X1701100Y182000D03*
X1688100Y184220D03*
X1697975Y181000D03*
X1704600Y201500D03*
X1685976Y181000D03*
X1702075Y205500D03*
X1688692Y620191D03*
X1708692D03*
X1729255Y25347D03*
Y45347D03*
X1718675Y88000D03*
X1732786Y58461D03*
X1719075Y107016D03*
Y112000D03*
X1718675Y99000D03*
Y93500D03*
X1713524Y109500D03*
Y114500D03*
X1721685Y95940D03*
X1727200Y104500D03*
X1738000Y124500D03*
X1721000Y142525D03*
X1714100Y144925D03*
X1713525Y134500D03*
Y129500D03*
X1713524Y119500D03*
X1729411Y143661D03*
X1727100Y164280D03*
X1715525Y168500D03*
Y153000D03*
X1722063Y156962D03*
X1726099Y153000D03*
X1720524Y175000D03*
X1717600Y158000D03*
X1720100Y179500D03*
X1729411Y159161D03*
X1733500Y173760D03*
X1712000Y153000D03*
X1728475Y175000D03*
X1731925Y199000D03*
X1714175Y187000D03*
X1738740Y191500D03*
X1729000Y183500D03*
X1724824Y205276D03*
X1711025Y187000D03*
X1721500Y205000D03*
X1721600Y194760D03*
Y198500D03*
X1729275Y562751D03*
Y542751D03*
Y582751D03*
Y602751D03*
X1753635Y69037D03*
X1767525Y114016D03*
X1759600Y114500D03*
X1767425Y107000D03*
X1761600Y124524D03*
X1764000Y142525D03*
X1767425Y137000D03*
X1768500Y142525D03*
X1770575Y137000D03*
X1764100Y119500D03*
X1764000Y158025D03*
X1759925Y178900D03*
X1768500Y158025D03*
X1763925Y170984D03*
Y155484D03*
X1763075Y178900D03*
X1767075Y155484D03*
X1769476Y168500D03*
X1766925Y181500D03*
X1769425Y203000D03*
X1754925D03*
X1754260Y187260D03*
X1768000D03*
X1746000Y191240D03*
X1750563Y198000D03*
X1747925Y204000D03*
X1751600Y238000D03*
Y235500D03*
X1740600D03*
Y238000D03*
X1751600Y233000D03*
X1740600D03*
X1751600Y258000D03*
Y255500D03*
X1740600Y258000D03*
Y255500D03*
Y248000D03*
Y250500D03*
Y253000D03*
X1751600D03*
Y250500D03*
Y248000D03*
X1766432Y250301D03*
Y247301D03*
X1766447Y239798D03*
Y242798D03*
X1751600Y240500D03*
X1740600D03*
X1769300Y329400D03*
Y340600D03*
X1769692Y334649D03*
X1767700Y346200D03*
X1767600Y350000D03*
X1755454Y515746D03*
X1793635Y69037D03*
X1773635D03*
X1772975Y109500D03*
Y104500D03*
X1773076Y117500D03*
X1773000Y142525D03*
X1773500Y129500D03*
X1772975Y124500D03*
X1773000Y158000D03*
X1772600Y177300D03*
X1772500Y174000D03*
X1800100Y187500D03*
X1770075Y181500D03*
X1778000Y189500D03*
X1789600Y247000D03*
X1783932Y250357D03*
Y247357D03*
X1775432Y250357D03*
Y247357D03*
X1783947Y239798D03*
Y242798D03*
X1775447Y239798D03*
Y242798D03*
X1789600Y243500D03*
X1795600Y308000D03*
X1777375Y356300D03*
X1777383Y352305D03*
X1784035Y389535D03*
X1781535D03*
X1784035Y386935D03*
X1781535D03*
X1778838Y389508D03*
Y386908D03*
X1781535Y402935D03*
X1784035D03*
X1778838Y402908D03*
X1781535Y405535D03*
X1784035D03*
X1778838Y405508D03*
X1775454Y515746D03*
X1813635Y69037D03*
X1817500Y188000D03*
X1809600Y195000D03*
X1811500Y186000D03*
X1815454Y515746D03*
X1853635Y69037D03*
X1833635D03*
X1842164Y419238D03*
X1847164D03*
X1837164D03*
X1852164D03*
X1842164Y432338D03*
X1847164Y430568D03*
X1852164Y435538D03*
X1837164Y428238D03*
X1835454Y515746D03*
X1855509Y515697D03*
X1871008Y117112D03*
X1871009Y93913D03*
X1871008Y137112D03*
Y177112D03*
Y157112D03*
Y197112D03*
Y237112D03*
Y217112D03*
Y257112D03*
Y297112D03*
Y277112D03*
Y317112D03*
Y357112D03*
Y337112D03*
Y377112D03*
Y417112D03*
Y397112D03*
Y437112D03*
Y477112D03*
Y457112D03*
Y497112D03*
G54D44*
X1673228Y222834D03*
X1663385Y226771D03*
X1659448Y236614D03*
X1663385Y246457D03*
X1673228Y250394D03*
X1687008Y236614D03*
X1683071Y226771D03*
Y246457D03*
G54D19*
X166785Y200472D03*
Y280472D03*
Y360472D03*
Y440472D03*
Y520472D03*
X243785Y200472D03*
Y280472D03*
Y360472D03*
Y440472D03*
Y520472D03*
X1488500Y200472D03*
Y280472D03*
Y360472D03*
Y440472D03*
Y520472D03*
X1565500Y200472D03*
Y280472D03*
Y360472D03*
Y440472D03*
Y520472D03*
G54D49*
X1848957Y324213D03*
X1843957Y329213D03*
X1848957Y314213D03*
X1843957Y319213D03*
X1853957Y329213D03*
Y319213D03*
X1848957Y334213D03*
Y344213D03*
X1843957Y339213D03*
Y349213D03*
X1853957D03*
Y339213D03*
X1858957Y344213D03*
Y334213D03*
G54D15*
X45275Y236614D03*
Y411594D03*
X72835Y236614D03*
X68898Y226771D03*
X59055Y222834D03*
X49212Y226771D03*
X68898Y246457D03*
X49212D03*
X59055Y250394D03*
X68898Y421437D03*
X72835Y411594D03*
X68898Y401751D03*
X59055Y397814D03*
X49212Y401751D03*
Y421437D03*
X59055Y425374D03*
X1673228Y397834D03*
X1663385Y401771D03*
X1659448Y411614D03*
X1663385Y421457D03*
X1673228Y425394D03*
X1683071Y421457D03*
X1687008Y411614D03*
X1683071Y401771D03*
G54D43*
X1642915Y111950D03*
X1639372Y114450D03*
X1646458Y111950D03*
X1642915Y114450D03*
X1639372Y111950D03*
X1646458Y114450D03*
X1650002Y111950D03*
Y114450D03*
G54D29*
X454738Y56000D03*
X451738D03*
X448738D03*
X445738D03*
X442738D03*
X454738Y68000D03*
Y65000D03*
Y62000D03*
Y59000D03*
X451738D03*
Y62000D03*
Y65000D03*
Y68000D03*
X448738Y59000D03*
Y62000D03*
Y65000D03*
Y68000D03*
X445738Y59000D03*
Y62000D03*
Y65000D03*
Y68000D03*
X442738Y59000D03*
Y62000D03*
Y65000D03*
Y68000D03*
X454738Y112400D03*
Y109400D03*
Y106400D03*
Y103400D03*
X451738D03*
Y106400D03*
Y109400D03*
Y112400D03*
X448738Y103400D03*
Y106400D03*
Y109400D03*
Y112400D03*
X445738Y103400D03*
Y106400D03*
Y109400D03*
Y112400D03*
X442738Y103400D03*
Y106400D03*
Y109400D03*
Y112400D03*
X454738Y100400D03*
X451738D03*
X448738D03*
X445738D03*
X442738D03*
X454738Y147800D03*
X451738D03*
X448738D03*
X445738D03*
X442738D03*
X454738Y144800D03*
X451738D03*
X448738D03*
X445738D03*
X442738D03*
X454738Y156800D03*
Y153800D03*
Y150800D03*
X451738D03*
Y153800D03*
Y156800D03*
X448738Y150800D03*
Y153800D03*
Y156800D03*
X445738Y150800D03*
Y153800D03*
Y156800D03*
X442738Y150800D03*
Y153800D03*
Y156800D03*
X454738Y201200D03*
Y198200D03*
Y195200D03*
Y192200D03*
X451738D03*
Y195200D03*
Y198200D03*
Y201200D03*
X448738Y192200D03*
Y195200D03*
Y198200D03*
Y201200D03*
X445738Y192200D03*
Y195200D03*
Y198200D03*
Y201200D03*
X442738Y192200D03*
Y195200D03*
Y198200D03*
Y201200D03*
X454738Y189200D03*
X451738D03*
X448738D03*
X445738D03*
X442738D03*
X454738Y239600D03*
Y236600D03*
X451738D03*
Y239600D03*
X448738Y236600D03*
Y239600D03*
X445738Y236600D03*
Y239600D03*
X442738Y236600D03*
Y239600D03*
X454738Y233600D03*
X451738D03*
X448738D03*
X445738D03*
X442738D03*
X454738Y245600D03*
Y242600D03*
X451738D03*
Y245600D03*
X448738Y242600D03*
Y245600D03*
X445738Y242600D03*
Y245600D03*
X442738Y242600D03*
Y245600D03*
X448738Y278000D03*
X451738D03*
X454738D03*
X448738Y290000D03*
Y287000D03*
Y284000D03*
Y281000D03*
X451738Y290000D03*
Y287000D03*
Y284000D03*
Y281000D03*
X454738D03*
Y284000D03*
Y287000D03*
Y290000D03*
X445738D03*
Y287000D03*
Y284000D03*
Y281000D03*
Y278000D03*
X442738Y290000D03*
Y287000D03*
Y284000D03*
Y281000D03*
Y278000D03*
X455946Y357216D03*
X458946D03*
X468946Y357016D03*
X465946D03*
X471946D03*
X528084Y77900D03*
Y74900D03*
Y71900D03*
X525084Y77900D03*
Y74900D03*
Y71900D03*
X522084Y77900D03*
Y74900D03*
Y71900D03*
X525084Y116300D03*
X522084D03*
X528084D03*
X525084Y122300D03*
X522084D03*
X525084Y119300D03*
X522084D03*
X528084Y122300D03*
Y119300D03*
X525084Y166700D03*
X522084D03*
X525084Y160700D03*
Y163700D03*
X522084D03*
Y160700D03*
Y205100D03*
Y208100D03*
X525084D03*
Y205100D03*
X522084Y211100D03*
X525084D03*
X522084Y249500D03*
Y252500D03*
X525084D03*
Y249500D03*
X522084Y255500D03*
X525084D03*
X528084Y252500D03*
Y249500D03*
Y255500D03*
Y299900D03*
X525084D03*
X522084D03*
X528084Y296900D03*
X525084D03*
X522084D03*
X528084Y293900D03*
X525084D03*
X522084D03*
X531084Y77900D03*
Y74900D03*
Y71900D03*
Y299900D03*
Y296900D03*
Y293900D03*
X586184Y117800D03*
X583184D03*
X580184D03*
X586184Y114800D03*
X583184D03*
X580184D03*
X586184Y111800D03*
X583184D03*
X580184D03*
X586184Y108800D03*
X583184D03*
X580184D03*
X586184Y105800D03*
X583184D03*
X580184D03*
Y126800D03*
X583184D03*
X586184D03*
Y123800D03*
X583184D03*
X580184D03*
X586184Y120800D03*
X583184D03*
X580184D03*
X583184Y239000D03*
X580184D03*
X583184Y242000D03*
X580184D03*
X583184Y254000D03*
Y251000D03*
Y248000D03*
Y245000D03*
X580184D03*
Y248000D03*
Y251000D03*
Y254000D03*
X583184Y260000D03*
Y257000D03*
X580184D03*
Y260000D03*
X620466Y246839D03*
X590684Y313800D03*
Y310800D03*
X664484Y212500D03*
X666984D03*
X672484D03*
X674984D03*
X679484D03*
X681984D03*
X685484D03*
X687984D03*
X1240200Y77900D03*
Y74900D03*
Y71900D03*
Y68900D03*
Y65900D03*
X1237200D03*
Y68900D03*
Y71900D03*
Y74900D03*
Y77900D03*
X1234200Y65900D03*
Y68900D03*
Y71900D03*
Y74900D03*
Y77900D03*
X1231200Y65900D03*
Y68900D03*
Y71900D03*
Y74900D03*
Y77900D03*
X1234200Y116300D03*
Y113300D03*
Y110300D03*
X1237200Y116300D03*
Y113300D03*
Y110300D03*
X1240200D03*
Y113300D03*
Y116300D03*
X1234200Y122300D03*
Y119300D03*
X1237200Y122300D03*
Y119300D03*
X1240200D03*
Y122300D03*
X1237200Y166700D03*
Y163700D03*
Y160700D03*
Y157700D03*
Y154700D03*
X1240200D03*
Y157700D03*
Y160700D03*
Y163700D03*
Y166700D03*
X1237200Y208100D03*
X1240200D03*
X1237200Y211100D03*
X1240200D03*
X1234200Y252500D03*
X1237200D03*
X1234200Y255500D03*
X1237200D03*
X1240200Y252500D03*
Y255500D03*
Y299900D03*
Y296900D03*
X1237200D03*
Y299900D03*
X1234200Y296900D03*
Y299900D03*
X1231200Y296900D03*
Y299900D03*
G54D30*
X649059Y314000D03*
X1728600Y387500D03*
X1731100D03*
X1733600D03*
X1762454Y320347D03*
X1742109Y345235D03*
Y342435D03*
X1747416Y348293D03*
X1747909Y345335D03*
Y342535D03*
X1744909Y345335D03*
Y342535D03*
X1742109Y339635D03*
Y336835D03*
Y334035D03*
X1747909Y339735D03*
Y336935D03*
Y334135D03*
X1744909Y339735D03*
Y336935D03*
Y334135D03*
X1767151Y333311D03*
X1777532Y328322D03*
X1777459Y332322D03*
X1777383Y348288D03*
G54D35*
X802087Y200984D03*
X792087D03*
X822087D03*
X812087D03*
X920197D03*
X910197D03*
X940197D03*
X930197D03*
G54D38*
X825900Y362200D03*
Y372200D03*
X866400Y362200D03*
Y382200D03*
X906900Y362200D03*
Y372200D03*
G54D18*
X137303Y601693D03*
Y609567D03*
Y617441D03*
Y625315D03*
Y633189D03*
Y641063D03*
Y648937D03*
Y656811D03*
Y664685D03*
X145177Y601693D03*
Y609567D03*
Y617441D03*
Y625315D03*
Y633189D03*
Y641063D03*
Y648937D03*
Y656811D03*
Y664685D03*
X1576280Y601693D03*
X1568406D03*
X1576280Y609567D03*
Y617441D03*
Y625315D03*
Y633189D03*
X1568406Y609567D03*
Y617441D03*
Y625315D03*
Y633189D03*
X1576280Y641063D03*
Y648937D03*
Y656811D03*
X1568406Y641063D03*
Y648937D03*
Y656811D03*
X1576280Y664685D03*
X1568406D03*
G54D32*
X681498Y575042D03*
Y565042D03*
X681604Y593187D03*
Y603187D03*
X997833Y575042D03*
Y565042D03*
Y593187D03*
Y603187D03*
G54D45*
X1848583Y99212D03*
X1848582Y481693D03*
G54D21*
X163878Y601693D03*
X156004D03*
X163878Y609567D03*
Y617441D03*
Y625315D03*
Y633189D03*
X156004Y609567D03*
Y617441D03*
Y625315D03*
Y633189D03*
X163878Y641063D03*
Y648937D03*
Y656811D03*
X156004Y641063D03*
Y648937D03*
Y656811D03*
X163878Y664685D03*
X156004D03*
X192126Y656811D03*
Y648937D03*
Y664685D03*
X215748Y656811D03*
Y648937D03*
X223622Y656811D03*
Y648937D03*
X200000Y656811D03*
Y648937D03*
X215748Y664685D03*
X223622D03*
X200000D03*
X250866Y20827D03*
X255906Y648937D03*
X248032D03*
X255906Y656811D03*
X248032D03*
X255906Y664685D03*
X248032D03*
X279646Y23012D03*
Y13012D03*
X284646Y18012D03*
X274646D03*
X284646Y8012D03*
X274646D03*
X260866Y20827D03*
X279528Y648937D03*
X271654D03*
X279528Y656811D03*
X271654D03*
X279528Y664685D03*
X271654D03*
X289646Y23012D03*
Y13012D03*
X303150Y648937D03*
X295276D03*
X303150Y656811D03*
X295276D03*
X303150Y664685D03*
X295276D03*
X1437008Y648937D03*
X1429134D03*
X1437008Y656811D03*
X1429134D03*
X1437008Y664685D03*
X1429134D03*
X1465197Y18012D03*
Y8012D03*
X1451417Y20827D03*
X1441417D03*
X1460630Y648937D03*
X1452756D03*
X1460630Y656811D03*
X1452756D03*
X1460630Y664685D03*
X1452756D03*
X1480197Y23012D03*
X1470197D03*
X1480197Y13012D03*
X1470197D03*
X1475197Y18012D03*
Y8012D03*
X1484252Y648937D03*
X1476378D03*
X1484252Y656811D03*
X1476378D03*
X1484252Y664685D03*
X1476378D03*
X1508661Y656811D03*
Y648937D03*
X1516535Y656811D03*
Y648937D03*
X1508661Y664685D03*
X1516535D03*
X1532283Y656811D03*
Y648937D03*
X1540157Y656811D03*
Y648937D03*
X1532283Y664685D03*
X1540157D03*
X1587107Y601693D03*
Y609567D03*
Y617441D03*
Y625315D03*
Y633189D03*
Y641063D03*
Y648937D03*
Y656811D03*
Y664685D03*
X1594981Y601693D03*
Y609567D03*
Y617441D03*
Y625315D03*
Y633189D03*
Y641063D03*
Y648937D03*
Y656811D03*
Y664685D03*
G54D47*
X1846142Y230433D03*
Y240433D03*
X1856772D03*
Y230433D03*
X1846142Y250433D03*
Y260433D03*
Y270433D03*
X1856772D03*
Y260433D03*
Y250433D03*
X1846142Y280433D03*
Y290433D03*
Y300433D03*
X1856772D03*
Y290433D03*
Y280433D03*
X1858957Y324213D03*
Y314213D03*
G54D39*
X825900Y382200D03*
X906900D03*
G54D42*
X1011017Y598187D03*
G54D41*
Y570042D03*
G54D25*
X207874Y639095D03*
X1524409D03*
G54D14*
X47244Y17716D03*
Y330708D03*
X748032Y64961D03*
Y344488D03*
X984252Y64961D03*
Y344488D03*
X1685040Y17716D03*
Y330708D03*
X1799212Y96457D03*
Y478346D03*
G54D28*
X287402Y628465D03*
X263780Y659961D03*
X1468504Y628465D03*
X1444882Y659961D03*
G54D10*
X19685Y-774040D03*
Y766166D03*
X240866Y15512D03*
X300866Y10197D03*
X566575Y463701D03*
D03*
D03*
X1431417Y15512D03*
X1491417Y10197D03*
X1854331Y-774040D03*
Y766166D03*
G54D48*
X1851457Y220433D03*
X1856772Y360433D03*
G54D23*
X231600Y81000D03*
X1212478Y300181D03*
X1529100Y78500D03*
G54D36*
X822087Y88484D03*
Y313484D03*
X940197Y88484D03*
Y313484D03*
G54D22*
X192126Y633189D03*
Y625315D03*
Y617441D03*
X200000Y633189D03*
Y625315D03*
Y617441D03*
X215748Y633189D03*
Y625315D03*
Y617441D03*
X223622Y633189D03*
Y625315D03*
Y617441D03*
X255906D03*
X248032D03*
X255906Y625315D03*
Y633189D03*
X248032D03*
Y625315D03*
X279528Y617441D03*
X271654D03*
X279528Y625315D03*
Y633189D03*
X271654D03*
Y625315D03*
X295276Y617441D03*
Y625315D03*
Y633189D03*
X303150D03*
Y625315D03*
Y617441D03*
X1437008D03*
X1429134D03*
X1437008Y625315D03*
Y633189D03*
X1429134D03*
Y625315D03*
X1460630Y617441D03*
X1452756D03*
X1460630Y625315D03*
Y633189D03*
X1452756D03*
Y625315D03*
X1476378Y617441D03*
Y625315D03*
Y633189D03*
X1484252D03*
Y625315D03*
Y617441D03*
X1508661Y633189D03*
Y625315D03*
Y617441D03*
X1516535Y633189D03*
Y625315D03*
Y617441D03*
X1532283Y633189D03*
Y625315D03*
Y617441D03*
X1540157Y633189D03*
Y625315D03*
Y617441D03*
G54D26*
X250866Y10197D03*
X260866D03*
X1451417D03*
X1441417D03*
G54D24*
X225829Y103412D03*
Y99503D03*
X225953Y95780D03*
X225891Y92305D03*
X622288Y235790D03*
X624788D03*
X1733600Y397500D03*
X1731100D03*
X1728600D03*
G54D17*
X137355Y120500D03*
X205061Y85500D03*
Y79000D03*
Y75000D03*
Y71500D03*
Y67500D03*
Y89500D03*
Y93000D03*
Y97000D03*
X200600Y109059D03*
X205100Y123000D03*
X325500Y15000D03*
Y18000D03*
Y21000D03*
X340500D03*
Y18000D03*
Y15000D03*
X337500Y21000D03*
Y18000D03*
Y15000D03*
X334500Y21000D03*
Y18000D03*
Y15000D03*
X331500Y21000D03*
Y18000D03*
Y15000D03*
X328500Y21000D03*
Y18000D03*
Y15000D03*
X441938Y87700D03*
Y132100D03*
Y176500D03*
Y220900D03*
Y265300D03*
Y309700D03*
X498923Y37456D03*
X495923D03*
X492923D03*
X489923D03*
X501923D03*
X504923D03*
X510923D03*
X507923D03*
X528084Y68900D03*
Y65900D03*
X525084Y68900D03*
Y65900D03*
X522084Y68900D03*
Y65900D03*
X525084Y113300D03*
Y110300D03*
X522084Y113300D03*
Y110300D03*
X528084Y113300D03*
Y110300D03*
X525084Y157700D03*
Y154700D03*
X522084Y157700D03*
Y154700D03*
Y199100D03*
Y202100D03*
X525084Y199100D03*
Y202100D03*
X522084Y243500D03*
Y246500D03*
X525084Y243500D03*
Y246500D03*
X528084Y243500D03*
Y246500D03*
Y290900D03*
Y287900D03*
X525084D03*
Y290900D03*
X522084D03*
Y287900D03*
X531084Y68900D03*
Y65900D03*
Y290900D03*
Y287900D03*
X645784Y43500D03*
X648784D03*
X645784Y40500D03*
X648784D03*
X645784Y99000D03*
X648784D03*
X645784Y96000D03*
X648784D03*
X641000Y261500D03*
X651784Y43500D03*
Y40500D03*
X657784D03*
X654784D03*
X657784Y43500D03*
X654784D03*
X651784Y99000D03*
Y96000D03*
X657784D03*
X654784D03*
X657784Y99000D03*
X654784D03*
X659000Y284000D03*
X671000Y315760D03*
X668000Y311500D03*
X663500D03*
X657500Y326925D03*
X693863Y189760D03*
X688900Y184260D03*
X704200Y206569D03*
X736554Y131056D03*
Y128056D03*
X739554Y131056D03*
Y128056D03*
X742554D03*
X732100Y185000D03*
X729100D03*
X726100D03*
X720100D03*
X723100D03*
X726100Y188000D03*
X729100D03*
X732100D03*
X723100D03*
X720100D03*
X726000Y231500D03*
X729000D03*
X723000D03*
X720000D03*
X732000D03*
Y228500D03*
X720000D03*
X723000D03*
X726000D03*
X729000D03*
X719500Y315500D03*
X734500Y310575D03*
X742554Y131056D03*
X749600Y185000D03*
X752600D03*
X755600D03*
X758600D03*
X746600Y188000D03*
X758600D03*
X755600D03*
X752600D03*
X749600D03*
X746600Y185000D03*
X758500Y231500D03*
X746500D03*
X755500D03*
X752500D03*
X749500D03*
X746500Y228500D03*
X755500D03*
X752500D03*
X749500D03*
X758500D03*
X880500Y369500D03*
X983500Y185000D03*
Y188000D03*
X980500Y185000D03*
X974500D03*
X977500D03*
X980500Y188000D03*
X977500D03*
X974500D03*
Y231500D03*
X977500D03*
X983500D03*
X980500D03*
X983500Y228500D03*
X980500D03*
X977500D03*
X974500D03*
X990954Y131056D03*
Y128056D03*
X993954Y131056D03*
Y128056D03*
X996954D03*
Y131056D03*
X986500Y185000D03*
Y188000D03*
X1004000Y185000D03*
X1001000Y188000D03*
X1004000D03*
X1007000Y185000D03*
X1010000D03*
X1013000D03*
Y188000D03*
X1010000D03*
X1007000D03*
X1001000Y185000D03*
X1004000Y231500D03*
X1007000D03*
X1010000D03*
X1001000D03*
X986500D03*
X1013000D03*
X986500Y228500D03*
X1013000D03*
X1004000D03*
X1007000D03*
X1010000D03*
X1001000D03*
X1074500Y43500D03*
Y99000D03*
X1065800Y339500D03*
X1063300D03*
X1073800D03*
X1071300D03*
X1077500Y43500D03*
Y40500D03*
X1074500D03*
X1080500D03*
X1083500D03*
X1086500D03*
X1080500Y43500D03*
X1083500D03*
X1086500D03*
X1077500Y99000D03*
Y96000D03*
X1074500D03*
X1080500D03*
X1083500D03*
X1086500D03*
X1080500Y99000D03*
X1083500D03*
X1086500D03*
X1101500Y268500D03*
X1081800Y339500D03*
X1079300D03*
X1086800D03*
X1089300D03*
X1118500Y283000D03*
X1106000Y364500D03*
X1112500Y364700D03*
X1122000Y366240D03*
X1155366Y38982D03*
X1152366D03*
X1158366D03*
X1161366D03*
X1143500Y251500D03*
X1141600Y305161D03*
X1154600Y321050D03*
X1143100Y322500D03*
Y320000D03*
X1147000Y342500D03*
X1135000Y366500D03*
X1139000D03*
X1176100Y105800D03*
Y108800D03*
X1182100Y105800D03*
Y108800D03*
X1179100D03*
Y105800D03*
X1176100Y111800D03*
Y114800D03*
Y117800D03*
X1182100Y111800D03*
Y114800D03*
Y117800D03*
X1179100D03*
Y114800D03*
Y111800D03*
X1176100Y126800D03*
Y123800D03*
Y120800D03*
X1182100Y126800D03*
Y123800D03*
Y120800D03*
X1179100D03*
Y123800D03*
Y126800D03*
X1176100Y239000D03*
X1171600Y238000D03*
X1179100Y239000D03*
X1182100D03*
X1176100Y254000D03*
Y251000D03*
Y248000D03*
Y245000D03*
Y257000D03*
Y260000D03*
Y242000D03*
X1171600Y241500D03*
X1179100Y242000D03*
Y260000D03*
Y257000D03*
Y245000D03*
Y248000D03*
Y251000D03*
Y254000D03*
X1182100D03*
Y251000D03*
Y248000D03*
Y245000D03*
Y257000D03*
Y260000D03*
Y242000D03*
X1165575Y340500D03*
X1171700Y349900D03*
X1178500Y368740D03*
X1223866Y38482D03*
X1220866D03*
X1225930Y359148D03*
X1226866Y38482D03*
X1229866D03*
X1237200Y205100D03*
Y202100D03*
Y199100D03*
X1240200D03*
Y202100D03*
Y205100D03*
X1234200Y249500D03*
Y246500D03*
Y243500D03*
X1237200Y249500D03*
Y246500D03*
Y243500D03*
X1240200D03*
Y246500D03*
Y249500D03*
Y293900D03*
Y290900D03*
Y287900D03*
X1237200D03*
Y290900D03*
Y293900D03*
X1234200Y287900D03*
Y290900D03*
Y293900D03*
X1231200D03*
Y290900D03*
Y287900D03*
X1242930Y359148D03*
Y356148D03*
X1245930Y359148D03*
Y356148D03*
X1248930Y359148D03*
Y356148D03*
X1231930D03*
Y359148D03*
X1228930Y356148D03*
Y359148D03*
X1225930Y356148D03*
X1253930Y379648D03*
X1250930D03*
X1247930D03*
X1264366Y38482D03*
X1261366D03*
X1267366D03*
X1270366D03*
X1260340Y359284D03*
Y356284D03*
X1263340Y359284D03*
Y356284D03*
X1266340Y359284D03*
Y356284D03*
X1286113Y378312D03*
X1265340Y379784D03*
X1268340D03*
X1271340D03*
X1307700Y78900D03*
Y81900D03*
X1310700D03*
Y78900D03*
X1313700Y81900D03*
Y78900D03*
X1307700Y84900D03*
Y87900D03*
X1310700D03*
Y84900D03*
X1313700Y87900D03*
Y84900D03*
X1307700Y90900D03*
X1310700D03*
X1313700D03*
X1307700Y123300D03*
Y126300D03*
X1310700D03*
Y123300D03*
X1313700Y126300D03*
Y123300D03*
X1307700Y129300D03*
Y132300D03*
Y135300D03*
X1310700D03*
Y132300D03*
Y129300D03*
X1313700Y135300D03*
Y132300D03*
Y129300D03*
Y167700D03*
Y170700D03*
Y173700D03*
Y176700D03*
X1310700Y167700D03*
Y170700D03*
Y173700D03*
Y176700D03*
X1307700D03*
Y173700D03*
Y170700D03*
Y167700D03*
X1313700Y179700D03*
X1310700D03*
X1307700D03*
Y212100D03*
Y215100D03*
X1310700D03*
Y212100D03*
X1313700Y215100D03*
Y212100D03*
X1307700Y218100D03*
Y221100D03*
Y224100D03*
X1310700D03*
Y221100D03*
Y218100D03*
X1313700Y224100D03*
Y221100D03*
Y218100D03*
X1307700Y256500D03*
Y259500D03*
X1310700D03*
Y256500D03*
X1313700Y259500D03*
Y256500D03*
X1307700Y262500D03*
Y265500D03*
Y268500D03*
X1310700D03*
Y265500D03*
Y262500D03*
X1313700Y268500D03*
Y265500D03*
Y262500D03*
X1307700Y300900D03*
Y303900D03*
X1310700D03*
Y300900D03*
X1313700Y303900D03*
Y300900D03*
X1307700Y306900D03*
Y309900D03*
Y312900D03*
X1310700D03*
Y309900D03*
Y306900D03*
X1313700Y309900D03*
Y306900D03*
X1286113Y375312D03*
X1289113Y378312D03*
Y375312D03*
X1292113Y378312D03*
Y375312D03*
Y372312D03*
X1289113D03*
X1316700Y81900D03*
Y78900D03*
X1319700Y81900D03*
Y78900D03*
X1316700Y87900D03*
Y84900D03*
X1319700Y87900D03*
Y84900D03*
X1320346Y67900D03*
X1316700Y90900D03*
X1319700D03*
X1320346Y112300D03*
X1316700Y126300D03*
Y123300D03*
X1319700Y126300D03*
Y123300D03*
X1316700Y135300D03*
Y132300D03*
Y129300D03*
X1319700Y135300D03*
Y132300D03*
Y129300D03*
Y167700D03*
Y170700D03*
Y173700D03*
Y176700D03*
X1316700Y167700D03*
Y170700D03*
Y173700D03*
Y176700D03*
X1320346Y156700D03*
Y201100D03*
X1316700Y215100D03*
Y212100D03*
X1319700Y215100D03*
Y212100D03*
X1316700Y224100D03*
Y221100D03*
Y218100D03*
X1319700Y224100D03*
Y221100D03*
Y218100D03*
X1316700Y259500D03*
Y256500D03*
X1319700Y259500D03*
Y256500D03*
X1316700Y268500D03*
Y265500D03*
Y262500D03*
X1319700Y268500D03*
Y265500D03*
Y262500D03*
X1320346Y245500D03*
Y289900D03*
X1316700Y303900D03*
Y300900D03*
X1319700Y303900D03*
Y300900D03*
X1316700Y306900D03*
X1406230Y21076D03*
Y18076D03*
Y15076D03*
X1403230Y21076D03*
Y18076D03*
Y15076D03*
X1400230Y21076D03*
Y18076D03*
Y15076D03*
X1397230D03*
Y18076D03*
Y21076D03*
X1412230D03*
Y18076D03*
Y15076D03*
X1409230Y21076D03*
Y18076D03*
Y15076D03*
X1764000Y107000D03*
X1763500Y113000D03*
X1751289Y345227D03*
X1747416Y351817D03*
X1747235Y355989D03*
Y359564D03*
Y363689D03*
Y367264D03*
Y371389D03*
Y374964D03*
X1773500Y121000D03*
X1776100Y361500D03*
Y371500D03*
Y368500D03*
X1776140Y364405D03*
X1844500Y416500D03*
X1847500Y437000D03*
G54D34*
X802087Y145984D03*
X792087D03*
X802087Y135984D03*
X792087D03*
X802087Y180984D03*
X792087D03*
X802087Y170984D03*
X792087D03*
X802087Y230984D03*
X792087D03*
X802087Y220984D03*
X792087D03*
X802087Y265984D03*
X792087D03*
X802087Y255984D03*
X792087D03*
X822087Y145984D03*
X812087D03*
X822087Y135984D03*
X812087D03*
X822087Y180984D03*
X812087D03*
X822087Y170984D03*
X812087D03*
X822087Y230984D03*
X812087D03*
X822087Y220984D03*
X812087D03*
X822087Y265984D03*
X812087D03*
X822087Y255984D03*
X812087D03*
X920197Y145984D03*
X910197D03*
X920197Y135984D03*
X910197D03*
X920197Y180984D03*
X910197D03*
X920197Y170984D03*
X910197D03*
X920197Y230984D03*
X910197D03*
X920197Y220984D03*
X910197D03*
X920197Y265984D03*
X910197D03*
X920197Y255984D03*
X910197D03*
X940197Y145984D03*
X930197D03*
X940197Y135984D03*
X930197D03*
X940197Y180984D03*
X930197D03*
X940197Y170984D03*
X930197D03*
X940197Y230984D03*
X930197D03*
X940197Y220984D03*
X930197D03*
X940197Y265984D03*
X930197D03*
X940197Y255984D03*
X930197D03*
G54D37*
X822087Y88484D03*
Y313484D03*
X940197Y88484D03*
Y313484D03*
G54D16*
X59055Y236614D03*
Y411594D03*
X1673228Y236614D03*
Y411614D03*
G54D46*
X1835739Y99212D03*
X1835738Y481693D03*
G54D12*
X32284Y541339D03*
X59055Y498032D03*
X1673228D03*
X1700000Y541339D03*
G54D40*
X866400Y372200D03*
G54D31*
X668314Y570042D03*
G54D33*
X668420Y598187D03*
%LPC*%
G75*
G54D20*
X166785Y230000D03*
Y310000D03*
Y390000D03*
Y470000D03*
Y550000D03*
X243785Y230000D03*
Y310000D03*
Y390000D03*
Y470000D03*
Y550000D03*
X1488500Y230000D03*
Y310000D03*
Y390000D03*
Y470000D03*
Y550000D03*
X1565500Y230000D03*
Y310000D03*
Y390000D03*
Y470000D03*
Y550000D03*
G54D50*
G01X163614Y226829D02*
X166785Y230000D01*
G01D02*
X169956Y233171D01*
G01X163614D02*
X166785Y230000D01*
G01D02*
X169956Y226829D01*
G01X163614Y306829D02*
X166785Y310000D01*
G01D02*
X169956Y313171D01*
G01X163614D02*
X166785Y310000D01*
G01D02*
X169956Y306829D01*
G01X163614Y386829D02*
X166785Y390000D01*
G01D02*
X169956Y393171D01*
G01X163614D02*
X166785Y390000D01*
G01D02*
X169956Y386829D01*
G01X163614Y466829D02*
X166785Y470000D01*
G01D02*
X169956Y473171D01*
G01X163614D02*
X166785Y470000D01*
G01D02*
X169956Y466829D01*
G01X166785Y550000D02*
X169956Y546829D01*
G01X163614Y553171D02*
X166785Y550000D01*
G01D02*
X169956Y553171D01*
G01X163614Y546829D02*
X166785Y550000D01*
G01X240614Y226829D02*
X243785Y230000D01*
G01D02*
X246956Y233171D01*
G01X240614D02*
X243785Y230000D01*
G01D02*
X246956Y226829D01*
G01X240614Y306829D02*
X243785Y310000D01*
G01D02*
X246956Y313171D01*
G01X240614D02*
X243785Y310000D01*
G01D02*
X246956Y306829D01*
G01X240614Y386829D02*
X243785Y390000D01*
G01D02*
X246956Y393171D01*
G01X240614D02*
X243785Y390000D01*
G01D02*
X246956Y386829D01*
G01X240614Y466829D02*
X243785Y470000D01*
G01D02*
X246956Y473171D01*
G01X240614D02*
X243785Y470000D01*
G01D02*
X246956Y466829D01*
G01X240614Y546829D02*
X243785Y550000D01*
G01D02*
X246956Y553171D01*
G01X240614D02*
X243785Y550000D01*
G01D02*
X246956Y546829D01*
G01X1485329Y226829D02*
X1488500Y230000D01*
G01D02*
X1491671Y233171D01*
G01X1485329D02*
X1488500Y230000D01*
G01D02*
X1491671Y226829D01*
G01X1485329Y306829D02*
X1488500Y310000D01*
G01D02*
X1491671Y313171D01*
G01X1485329D02*
X1488500Y310000D01*
G01D02*
X1491671Y306829D01*
G01X1485329Y386829D02*
X1488500Y390000D01*
G01D02*
X1491671Y393171D01*
G01X1485329D02*
X1488500Y390000D01*
G01D02*
X1491671Y386829D01*
G01X1485329Y466829D02*
X1488500Y470000D01*
G01D02*
X1491671Y473171D01*
G01X1485329D02*
X1488500Y470000D01*
G01D02*
X1491671Y466829D01*
G01X1485329Y546829D02*
X1488500Y550000D01*
G01D02*
X1491671Y553171D01*
G01X1485329D02*
X1488500Y550000D01*
G01D02*
X1491671Y546829D01*
G01X1562329Y226829D02*
X1565500Y230000D01*
G01D02*
X1568671Y233171D01*
G01X1562329D02*
X1565500Y230000D01*
G01D02*
X1568671Y226829D01*
G01X1562329Y306829D02*
X1565500Y310000D01*
G01D02*
X1568671Y313171D01*
G01X1562329D02*
X1565500Y310000D01*
G01D02*
X1568671Y306829D01*
G01X1562329Y386829D02*
X1565500Y390000D01*
G01D02*
X1568671Y393171D01*
G01X1562329D02*
X1565500Y390000D01*
G01D02*
X1568671Y386829D01*
G01X1562329Y466829D02*
X1565500Y470000D01*
G01D02*
X1568671Y473171D01*
G01X1562329D02*
X1565500Y470000D01*
G01D02*
X1568671Y466829D01*
G01X1562329Y546829D02*
X1565500Y550000D01*
G01D02*
X1568671Y553171D01*
G01X1562329D02*
X1565500Y550000D01*
G01D02*
X1568671Y546829D01*
G54D51*
G01X-457143Y-1211429D02*
Y2242857D01*
X4308572D01*
Y-1211429D01*
X-457143D01*
G01X37000Y-995000D02*
Y-1070000D01*
X537000D01*
Y-995000D01*
X37000D01*
G01X49000Y-1060000D02*
Y-1065000D01*
G01X47543Y-1060000D02*
X50457D01*
G01X55367Y-1065000D02*
X52833D01*
Y-1060000D01*
X55367D01*
G01X54353Y-1062417D02*
X52833D01*
G01X57933Y-1060000D02*
Y-1065000D01*
X60467D01*
G01X64300Y-1065167D02*
X64173Y-1065083D01*
Y-1064917D01*
X64300Y-1064833D01*
X64427Y-1064917D01*
Y-1065083D01*
X64300Y-1065167D01*
G01Y-1062917D02*
X64173Y-1062833D01*
Y-1062667D01*
X64300Y-1062583D01*
X64427Y-1062667D01*
Y-1062833D01*
X64300Y-1062917D01*
G01X69083Y-1066667D02*
X68450Y-1065833D01*
X68133Y-1065000D01*
Y-1061667D01*
X68450Y-1060833D01*
X69083Y-1060000D01*
G01X74500D02*
X73993Y-1060167D01*
X73613Y-1060583D01*
X73360Y-1061083D01*
X73170Y-1061750D01*
X73107Y-1062500D01*
X73170Y-1063250D01*
X73360Y-1063917D01*
X73613Y-1064417D01*
X73993Y-1064833D01*
X74500Y-1065000D01*
X75007Y-1064833D01*
X75387Y-1064417D01*
X75640Y-1063917D01*
X75830Y-1063250D01*
X75893Y-1062500D01*
X75830Y-1061750D01*
X75640Y-1061083D01*
X75387Y-1060583D01*
X75007Y-1060167D01*
X74500Y-1060000D01*
G01X78207Y-1064000D02*
X78587Y-1064583D01*
X79093Y-1064917D01*
X79663Y-1065000D01*
X80170Y-1064917D01*
X80677Y-1064500D01*
X80993Y-1064000D01*
X81057Y-1063500D01*
X80930Y-1062917D01*
X80487Y-1062500D01*
X80043Y-1062333D01*
X79473D01*
G01X80043D02*
X80423Y-1062083D01*
X80740Y-1061667D01*
X80867Y-1061167D01*
X80740Y-1060667D01*
X80423Y-1060250D01*
X79853Y-1060000D01*
X79283Y-1060083D01*
X78713Y-1060417D01*
G01X85017Y-1066667D02*
X85650Y-1065833D01*
X85967Y-1065000D01*
Y-1061667D01*
X85650Y-1060833D01*
X85017Y-1060000D01*
G01X88407Y-1064000D02*
X88787Y-1064583D01*
X89293Y-1064917D01*
X89863Y-1065000D01*
X90370Y-1064917D01*
X90877Y-1064500D01*
X91193Y-1064000D01*
X91257Y-1063500D01*
X91130Y-1062917D01*
X90687Y-1062500D01*
X90243Y-1062333D01*
X89673D01*
G01X90243D02*
X90623Y-1062083D01*
X90940Y-1061667D01*
X91067Y-1061167D01*
X90940Y-1060667D01*
X90623Y-1060250D01*
X90053Y-1060000D01*
X89483Y-1060083D01*
X88913Y-1060417D01*
G01X93697Y-1060833D02*
X94077Y-1060333D01*
X94520Y-1060083D01*
X95027Y-1060000D01*
X95660Y-1060167D01*
X96103Y-1060583D01*
X96230Y-1061083D01*
X96167Y-1061583D01*
X95913Y-1062000D01*
X94647Y-1062833D01*
X94077Y-1063417D01*
X93697Y-1064250D01*
X93570Y-1065000D01*
X96230D01*
G01X99873D02*
X100000Y-1063917D01*
X100190Y-1063000D01*
X100443Y-1062167D01*
X100760Y-1061250D01*
X101267Y-1060000D01*
X98733D01*
G01X104277Y-1063333D02*
X105923D01*
G01X108997Y-1060833D02*
X109377Y-1060333D01*
X109820Y-1060083D01*
X110327Y-1060000D01*
X110960Y-1060167D01*
X111403Y-1060583D01*
X111530Y-1061083D01*
X111467Y-1061583D01*
X111213Y-1062000D01*
X109947Y-1062833D01*
X109377Y-1063417D01*
X108997Y-1064250D01*
X108870Y-1065000D01*
X111530D01*
G01X113907Y-1064000D02*
X114287Y-1064583D01*
X114793Y-1064917D01*
X115363Y-1065000D01*
X115870Y-1064917D01*
X116377Y-1064500D01*
X116693Y-1064000D01*
X116757Y-1063500D01*
X116630Y-1062917D01*
X116187Y-1062500D01*
X115743Y-1062333D01*
X115173D01*
G01X115743D02*
X116123Y-1062083D01*
X116440Y-1061667D01*
X116567Y-1061167D01*
X116440Y-1060667D01*
X116123Y-1060250D01*
X115553Y-1060000D01*
X114983Y-1060083D01*
X114413Y-1060417D01*
G01X121160Y-1065000D02*
Y-1060000D01*
X118817Y-1063583D01*
X121983D01*
G01X124107Y-1064250D02*
X124487Y-1064667D01*
X124930Y-1064917D01*
X125500Y-1065000D01*
X126070Y-1064833D01*
X126513Y-1064500D01*
X126830Y-1063917D01*
X126893Y-1063250D01*
X126767Y-1062583D01*
X126450Y-1062167D01*
X126007Y-1061833D01*
X125563Y-1061750D01*
X125120Y-1061833D01*
X124550Y-1062167D01*
X124740Y-1060000D01*
X126450D01*
G01X134497Y-1065000D02*
Y-1060000D01*
X136903D01*
G01X136017Y-1062417D02*
X134497D01*
G01X139217Y-1065000D02*
X140800Y-1060000D01*
X142383Y-1065000D01*
G01X141813Y-1063250D02*
X139787D01*
G01X144570Y-1065000D02*
X147230Y-1060000D01*
G01X144570D02*
X147230Y-1065000D01*
G01X151000Y-1065167D02*
X150873Y-1065083D01*
Y-1064917D01*
X151000Y-1064833D01*
X151127Y-1064917D01*
Y-1065083D01*
X151000Y-1065167D01*
G01Y-1062917D02*
X150873Y-1062833D01*
Y-1062667D01*
X151000Y-1062583D01*
X151127Y-1062667D01*
Y-1062833D01*
X151000Y-1062917D01*
G01X155783Y-1066667D02*
X155150Y-1065833D01*
X154833Y-1065000D01*
Y-1061667D01*
X155150Y-1060833D01*
X155783Y-1060000D01*
G01X161200D02*
X160693Y-1060167D01*
X160313Y-1060583D01*
X160060Y-1061083D01*
X159870Y-1061750D01*
X159807Y-1062500D01*
X159870Y-1063250D01*
X160060Y-1063917D01*
X160313Y-1064417D01*
X160693Y-1064833D01*
X161200Y-1065000D01*
X161707Y-1064833D01*
X162087Y-1064417D01*
X162340Y-1063917D01*
X162530Y-1063250D01*
X162593Y-1062500D01*
X162530Y-1061750D01*
X162340Y-1061083D01*
X162087Y-1060583D01*
X161707Y-1060167D01*
X161200Y-1060000D01*
G01X164907Y-1064000D02*
X165287Y-1064583D01*
X165793Y-1064917D01*
X166363Y-1065000D01*
X166870Y-1064917D01*
X167377Y-1064500D01*
X167693Y-1064000D01*
X167757Y-1063500D01*
X167630Y-1062917D01*
X167187Y-1062500D01*
X166743Y-1062333D01*
X166173D01*
G01X166743D02*
X167123Y-1062083D01*
X167440Y-1061667D01*
X167567Y-1061167D01*
X167440Y-1060667D01*
X167123Y-1060250D01*
X166553Y-1060000D01*
X165983Y-1060083D01*
X165413Y-1060417D01*
G01X171717Y-1066667D02*
X172350Y-1065833D01*
X172667Y-1065000D01*
Y-1061667D01*
X172350Y-1060833D01*
X171717Y-1060000D01*
G01X175107Y-1064000D02*
X175487Y-1064583D01*
X175993Y-1064917D01*
X176563Y-1065000D01*
X177070Y-1064917D01*
X177577Y-1064500D01*
X177893Y-1064000D01*
X177957Y-1063500D01*
X177830Y-1062917D01*
X177387Y-1062500D01*
X176943Y-1062333D01*
X176373D01*
G01X176943D02*
X177323Y-1062083D01*
X177640Y-1061667D01*
X177767Y-1061167D01*
X177640Y-1060667D01*
X177323Y-1060250D01*
X176753Y-1060000D01*
X176183Y-1060083D01*
X175613Y-1060417D01*
G01X180523Y-1064417D02*
X180967Y-1064833D01*
X181473Y-1065000D01*
X181980Y-1064833D01*
X182423Y-1064333D01*
X182740Y-1063583D01*
X182867Y-1062833D01*
Y-1061917D01*
X182740Y-1061167D01*
X182423Y-1060500D01*
X182043Y-1060167D01*
X181600Y-1060000D01*
X181093Y-1060167D01*
X180713Y-1060500D01*
X180460Y-1061000D01*
X180333Y-1061667D01*
X180460Y-1062250D01*
X180777Y-1062833D01*
X181157Y-1063167D01*
X181600Y-1063250D01*
X182107Y-1063083D01*
X182487Y-1062667D01*
X182867Y-1061917D01*
G01X186573Y-1065000D02*
X186700Y-1063917D01*
X186890Y-1063000D01*
X187143Y-1062167D01*
X187460Y-1061250D01*
X187967Y-1060000D01*
X185433D01*
G01X190977Y-1063333D02*
X192623D01*
G01X195507Y-1064000D02*
X195887Y-1064583D01*
X196393Y-1064917D01*
X196963Y-1065000D01*
X197470Y-1064917D01*
X197977Y-1064500D01*
X198293Y-1064000D01*
X198357Y-1063500D01*
X198230Y-1062917D01*
X197787Y-1062500D01*
X197343Y-1062333D01*
X196773D01*
G01X197343D02*
X197723Y-1062083D01*
X198040Y-1061667D01*
X198167Y-1061167D01*
X198040Y-1060667D01*
X197723Y-1060250D01*
X197153Y-1060000D01*
X196583Y-1060083D01*
X196013Y-1060417D01*
G01X200797Y-1062917D02*
X201240Y-1062333D01*
X201620Y-1062000D01*
X202127Y-1061833D01*
X202570Y-1062000D01*
X202887Y-1062333D01*
X203140Y-1062833D01*
X203203Y-1063417D01*
X203140Y-1063917D01*
X202887Y-1064417D01*
X202507Y-1064833D01*
X202063Y-1065000D01*
X201557Y-1064833D01*
X201113Y-1064333D01*
X200860Y-1063583D01*
X200797Y-1062750D01*
X200923Y-1061667D01*
X201113Y-1061083D01*
X201430Y-1060500D01*
X201873Y-1060083D01*
X202317Y-1060000D01*
X202760Y-1060167D01*
X203077Y-1060583D01*
G01X207100Y-1065000D02*
Y-1060000D01*
X206340Y-1061000D01*
G01Y-1065000D02*
X207860D01*
G01X212960D02*
Y-1060000D01*
X210617Y-1063583D01*
X213783D01*
G01X232000Y-995000D02*
Y-1070000D01*
G01Y-1045000D02*
X335000D01*
Y-1020000D01*
G01X232000D02*
X335000D01*
G01X337000Y-995000D02*
Y-1070000D01*
G01X335000Y-995000D02*
Y-1070000D01*
G01X342507Y-1055000D02*
Y-1050000D01*
X343773D01*
X344280Y-1050250D01*
X344660Y-1050583D01*
X344977Y-1051083D01*
X345230Y-1051667D01*
X345293Y-1052500D01*
X345230Y-1053333D01*
X344977Y-1053917D01*
X344660Y-1054417D01*
X344280Y-1054750D01*
X343773Y-1055000D01*
X342507D01*
G01X347417D02*
X349000Y-1050000D01*
X350583Y-1055000D01*
G01X350013Y-1053250D02*
X347987D01*
G01X354100Y-1050000D02*
Y-1055000D01*
G01X352643Y-1050000D02*
X355557D01*
G01X360467Y-1055000D02*
X357933D01*
Y-1050000D01*
X360467D01*
G01X359453Y-1052417D02*
X357933D01*
G01X364300Y-1055167D02*
X364173Y-1055083D01*
Y-1054917D01*
X364300Y-1054833D01*
X364427Y-1054917D01*
Y-1055083D01*
X364300Y-1055167D01*
G01Y-1052917D02*
X364173Y-1052833D01*
Y-1052667D01*
X364300Y-1052583D01*
X364427Y-1052667D01*
Y-1052833D01*
X364300Y-1052917D01*
G01X337000Y-1045000D02*
X537000D01*
G01X342633Y-1030000D02*
Y-1025000D01*
X344153D01*
X344660Y-1025250D01*
X345040Y-1025833D01*
X345167Y-1026500D01*
X345040Y-1027167D01*
X344723Y-1027667D01*
X344153Y-1027917D01*
X342633D01*
G01X347860Y-1030167D02*
X350140Y-1025000D01*
G01X352643Y-1030000D02*
Y-1025000D01*
X355557Y-1030000D01*
Y-1025000D01*
G01X359200Y-1030167D02*
X359073Y-1030083D01*
Y-1029917D01*
X359200Y-1029833D01*
X359327Y-1029917D01*
Y-1030083D01*
X359200Y-1030167D01*
G01Y-1027917D02*
X359073Y-1027833D01*
Y-1027667D01*
X359200Y-1027583D01*
X359327Y-1027667D01*
Y-1027833D01*
X359200Y-1027917D01*
G01X342633Y-1005000D02*
Y-1000000D01*
X344153D01*
X344660Y-1000250D01*
X345040Y-1000833D01*
X345167Y-1001500D01*
X345040Y-1002167D01*
X344723Y-1002667D01*
X344153Y-1002917D01*
X342633D01*
G01X347733Y-1005000D02*
Y-1000000D01*
X349317D01*
X349823Y-1000250D01*
X350140Y-1000583D01*
X350267Y-1001250D01*
X350140Y-1001917D01*
X349760Y-1002333D01*
X349317Y-1002583D01*
X347733D01*
G01X349317D02*
X350267Y-1005000D01*
G01X354100D02*
X353593Y-1004917D01*
X353150Y-1004583D01*
X352770Y-1004083D01*
X352517Y-1003500D01*
X352390Y-1002833D01*
Y-1002167D01*
X352517Y-1001500D01*
X352770Y-1000917D01*
X353150Y-1000417D01*
X353593Y-1000083D01*
X354100Y-1000000D01*
X354607Y-1000083D01*
X355050Y-1000417D01*
X355430Y-1000917D01*
X355683Y-1001500D01*
X355810Y-1002167D01*
Y-1002833D01*
X355683Y-1003500D01*
X355430Y-1004083D01*
X355050Y-1004583D01*
X354607Y-1004917D01*
X354100Y-1005000D01*
G01X357933Y-1004000D02*
X358250Y-1004500D01*
X358630Y-1004833D01*
X359073Y-1005000D01*
X359580Y-1004833D01*
X359960Y-1004500D01*
X360340Y-1004000D01*
X360467Y-1003333D01*
Y-1000000D01*
G01X365567Y-1005000D02*
X363033D01*
Y-1000000D01*
X365567D01*
G01X364553Y-1002417D02*
X363033D01*
G01X370793Y-1000417D02*
X370413Y-1000167D01*
X369970Y-1000000D01*
X369463D01*
X368893Y-1000250D01*
X368450Y-1000667D01*
X368133Y-1001167D01*
X367880Y-1002000D01*
X367817Y-1002750D01*
X367943Y-1003500D01*
X368133Y-1004000D01*
X368513Y-1004500D01*
X368957Y-1004833D01*
X369400Y-1005000D01*
X369843D01*
X370287Y-1004833D01*
X370667Y-1004583D01*
X370983Y-1004250D01*
G01X374500Y-1000000D02*
Y-1005000D01*
G01X373043Y-1000000D02*
X375957D01*
G01X379600Y-1005167D02*
X379473Y-1005083D01*
Y-1004917D01*
X379600Y-1004833D01*
X379727Y-1004917D01*
Y-1005083D01*
X379600Y-1005167D01*
G01Y-1002917D02*
X379473Y-1002833D01*
Y-1002667D01*
X379600Y-1002583D01*
X379727Y-1002667D01*
Y-1002833D01*
X379600Y-1002917D01*
G01X337000Y-1020000D02*
X537000D01*
G01X452000Y-1045000D02*
Y-1070000D01*
G01X454633Y-1047500D02*
Y-1052500D01*
X457167D01*
G01X460240Y-1047500D02*
X461760D01*
G01X461000D02*
Y-1052500D01*
G01X460240D02*
X461760D01*
G01X466607Y-1049833D02*
X466860Y-1049583D01*
X467050Y-1049167D01*
X467177Y-1048583D01*
X467050Y-1048083D01*
X466797Y-1047750D01*
X466353Y-1047500D01*
X464643D01*
Y-1052500D01*
X466733D01*
X467177Y-1052167D01*
X467430Y-1051667D01*
X467557Y-1051083D01*
X467430Y-1050500D01*
X467050Y-1050000D01*
X466607Y-1049833D01*
X464643D01*
G01X471200Y-1052667D02*
X471073Y-1052583D01*
Y-1052417D01*
X471200Y-1052333D01*
X471327Y-1052417D01*
Y-1052583D01*
X471200Y-1052667D01*
G01Y-1050417D02*
X471073Y-1050333D01*
Y-1050167D01*
X471200Y-1050083D01*
X471327Y-1050167D01*
Y-1050333D01*
X471200Y-1050417D01*
G01X495000Y-1045000D02*
Y-1070000D01*
G01X498900Y-1047500D02*
Y-1052500D01*
G01X497443Y-1047500D02*
X500357D01*
G01X504000Y-1052500D02*
X503620Y-1052417D01*
X503240Y-1052083D01*
X502987Y-1051500D01*
X502860Y-1050833D01*
X502987Y-1050167D01*
X503240Y-1049583D01*
X503620Y-1049250D01*
X504000Y-1049167D01*
X504380Y-1049250D01*
X504760Y-1049583D01*
X505013Y-1050167D01*
X505077Y-1050833D01*
X505013Y-1051500D01*
X504760Y-1052083D01*
X504380Y-1052417D01*
X504000Y-1052500D01*
G01X509100D02*
X508720Y-1052417D01*
X508340Y-1052083D01*
X508087Y-1051500D01*
X507960Y-1050833D01*
X508087Y-1050167D01*
X508340Y-1049583D01*
X508720Y-1049250D01*
X509100Y-1049167D01*
X509480Y-1049250D01*
X509860Y-1049583D01*
X510113Y-1050167D01*
X510177Y-1050833D01*
X510113Y-1051500D01*
X509860Y-1052083D01*
X509480Y-1052417D01*
X509100Y-1052500D01*
G01X514200D02*
Y-1047500D01*
G01X519300Y-1052667D02*
X519173Y-1052583D01*
Y-1052417D01*
X519300Y-1052333D01*
X519427Y-1052417D01*
Y-1052583D01*
X519300Y-1052667D01*
G01Y-1050417D02*
X519173Y-1050333D01*
Y-1050167D01*
X519300Y-1050083D01*
X519427Y-1050167D01*
Y-1050333D01*
X519300Y-1050417D01*
G01X495000Y-1020000D02*
Y-1045000D01*
G01X497633Y-1027500D02*
Y-1022500D01*
X499217D01*
X499723Y-1022750D01*
X500040Y-1023083D01*
X500167Y-1023750D01*
X500040Y-1024417D01*
X499660Y-1024833D01*
X499217Y-1025083D01*
X497633D01*
G01X499217D02*
X500167Y-1027500D01*
G01X505267D02*
X502733D01*
Y-1022500D01*
X505267D01*
G01X504253Y-1024917D02*
X502733D01*
G01X507517Y-1022500D02*
X509100Y-1027500D01*
X510683Y-1022500D01*
G01X514200Y-1027667D02*
X514073Y-1027583D01*
Y-1027417D01*
X514200Y-1027333D01*
X514327Y-1027417D01*
Y-1027583D01*
X514200Y-1027667D01*
G01Y-1025417D02*
X514073Y-1025333D01*
Y-1025167D01*
X514200Y-1025083D01*
X514327Y-1025167D01*
Y-1025333D01*
X514200Y-1025417D01*
G01X503013Y-1073167D02*
X503120Y-1073042D01*
X503200Y-1072833D01*
X503253Y-1072542D01*
X503200Y-1072292D01*
X503093Y-1072125D01*
X502907Y-1072000D01*
X502187D01*
Y-1074500D01*
X503067D01*
X503253Y-1074333D01*
X503360Y-1074083D01*
X503413Y-1073792D01*
X503360Y-1073500D01*
X503200Y-1073250D01*
X503013Y-1073167D01*
X502187D01*
G01X505480Y-1074500D02*
Y-1072833D01*
G01Y-1073125D02*
X505373Y-1072958D01*
X505213Y-1072875D01*
X505027Y-1072833D01*
X504840Y-1072917D01*
X504680Y-1073083D01*
X504573Y-1073333D01*
X504520Y-1073667D01*
X504573Y-1074000D01*
X504680Y-1074250D01*
X504840Y-1074417D01*
X505027Y-1074500D01*
X505213Y-1074458D01*
X505373Y-1074333D01*
X505480Y-1074167D01*
G01X506800Y-1074208D02*
X506933Y-1074375D01*
X507120Y-1074500D01*
X507280D01*
X507440Y-1074417D01*
X507547Y-1074292D01*
X507600Y-1074125D01*
X507573Y-1073875D01*
X507467Y-1073750D01*
X506987Y-1073500D01*
X506880Y-1073208D01*
X506933Y-1073000D01*
X507040Y-1072875D01*
X507200Y-1072833D01*
X507360Y-1072875D01*
X507520Y-1073000D01*
G01X509000Y-1073375D02*
X509853D01*
X509773Y-1073083D01*
X509640Y-1072917D01*
X509453Y-1072833D01*
X509267Y-1072875D01*
X509107Y-1073000D01*
X509000Y-1073292D01*
X508947Y-1073542D01*
Y-1073792D01*
X509000Y-1074042D01*
X509133Y-1074292D01*
X509293Y-1074458D01*
X509480Y-1074500D01*
X509667Y-1074417D01*
X509853Y-1074167D01*
G01X511120Y-1074500D02*
Y-1072000D01*
G01Y-1073250D02*
X511253Y-1073000D01*
X511413Y-1072875D01*
X511573Y-1072833D01*
X511813Y-1072917D01*
X511973Y-1073083D01*
X512080Y-1073375D01*
Y-1073708D01*
X512027Y-1074042D01*
X511920Y-1074292D01*
X511733Y-1074458D01*
X511573Y-1074500D01*
X511413Y-1074458D01*
X511253Y-1074333D01*
X511120Y-1074125D01*
G01X513800Y-1074500D02*
X513640Y-1074458D01*
X513480Y-1074292D01*
X513373Y-1074000D01*
X513320Y-1073667D01*
X513373Y-1073333D01*
X513480Y-1073042D01*
X513640Y-1072875D01*
X513800Y-1072833D01*
X513960Y-1072875D01*
X514120Y-1073042D01*
X514227Y-1073333D01*
X514253Y-1073667D01*
X514227Y-1074000D01*
X514120Y-1074292D01*
X513960Y-1074458D01*
X513800Y-1074500D01*
G01X516480D02*
Y-1072833D01*
G01Y-1073125D02*
X516373Y-1072958D01*
X516213Y-1072875D01*
X516027Y-1072833D01*
X515840Y-1072917D01*
X515680Y-1073083D01*
X515573Y-1073333D01*
X515520Y-1073667D01*
X515573Y-1074000D01*
X515680Y-1074250D01*
X515840Y-1074417D01*
X516027Y-1074500D01*
X516213Y-1074458D01*
X516373Y-1074333D01*
X516480Y-1074167D01*
G01X517827Y-1074500D02*
Y-1072833D01*
G01Y-1073167D02*
X517960Y-1073000D01*
X518093Y-1072875D01*
X518280Y-1072833D01*
X518413Y-1072875D01*
X518573Y-1073000D01*
G01X520880Y-1072000D02*
Y-1074500D01*
G01Y-1074125D02*
X520773Y-1074333D01*
X520613Y-1074458D01*
X520427Y-1074500D01*
X520213Y-1074417D01*
X520053Y-1074208D01*
X519947Y-1073958D01*
X519920Y-1073667D01*
X519947Y-1073375D01*
X520053Y-1073125D01*
X520213Y-1072917D01*
X520427Y-1072833D01*
X520613Y-1072875D01*
X520747Y-1072958D01*
X520880Y-1073125D01*
G01X524267Y-1074500D02*
Y-1072000D01*
X524933D01*
X525147Y-1072125D01*
X525280Y-1072292D01*
X525333Y-1072625D01*
X525280Y-1072958D01*
X525120Y-1073167D01*
X524933Y-1073292D01*
X524267D01*
G01X524933D02*
X525333Y-1074500D01*
G01X526600Y-1073375D02*
X527453D01*
X527373Y-1073083D01*
X527240Y-1072917D01*
X527053Y-1072833D01*
X526867Y-1072875D01*
X526707Y-1073000D01*
X526600Y-1073292D01*
X526547Y-1073542D01*
Y-1073792D01*
X526600Y-1074042D01*
X526733Y-1074292D01*
X526893Y-1074458D01*
X527080Y-1074500D01*
X527267Y-1074417D01*
X527453Y-1074167D01*
G01X528720Y-1072833D02*
X529200Y-1074500D01*
X529680Y-1072833D01*
G01X531400Y-1074583D02*
X531347Y-1074542D01*
Y-1074458D01*
X531400Y-1074417D01*
X531453Y-1074458D01*
Y-1074542D01*
X531400Y-1074583D01*
G01X533600Y-1074500D02*
X533787Y-1074458D01*
X534000Y-1074333D01*
X534133Y-1074125D01*
X534187Y-1073833D01*
X534133Y-1073542D01*
X533973Y-1073292D01*
X533733Y-1073167D01*
X533467D01*
X533307Y-1073083D01*
X533173Y-1072875D01*
X533120Y-1072583D01*
X533200Y-1072292D01*
X533387Y-1072083D01*
X533600Y-1072000D01*
X533813Y-1072083D01*
X534000Y-1072292D01*
X534080Y-1072583D01*
X534027Y-1072875D01*
X533893Y-1073083D01*
X533733Y-1073167D01*
X533467D01*
X533227Y-1073292D01*
X533067Y-1073542D01*
X533013Y-1073833D01*
X533067Y-1074125D01*
X533200Y-1074333D01*
X533413Y-1074458D01*
X533600Y-1074500D01*
G01X536013Y-1073167D02*
X536120Y-1073042D01*
X536200Y-1072833D01*
X536253Y-1072542D01*
X536200Y-1072292D01*
X536093Y-1072125D01*
X535907Y-1072000D01*
X535187D01*
Y-1074500D01*
X536067D01*
X536253Y-1074333D01*
X536360Y-1074083D01*
X536413Y-1073792D01*
X536360Y-1073500D01*
X536200Y-1073250D01*
X536013Y-1073167D01*
X535187D01*
G01X-457143Y-1211429D02*
Y2242857D01*
X4308572D01*
Y-1211429D01*
X-457143D01*
G01X71650Y-1024800D02*
X69130Y-1024383D01*
X66925Y-1022717D01*
X65035Y-1020217D01*
X63775Y-1017300D01*
X63145Y-1013967D01*
Y-1010633D01*
X63775Y-1007300D01*
X65035Y-1004383D01*
X66925Y-1001884D01*
X69130Y-1000217D01*
X71650Y-999800D01*
X74170Y-1000217D01*
X76375Y-1001884D01*
X78265Y-1004383D01*
X79525Y-1007300D01*
X80155Y-1010633D01*
Y-1013967D01*
X79525Y-1017300D01*
X78265Y-1020217D01*
X76375Y-1022717D01*
X74170Y-1024383D01*
X71650Y-1024800D01*
G01X74170Y-1018133D02*
X77950Y-1024800D01*
G01X91495Y-1008134D02*
Y-1019800D01*
X92755Y-1022717D01*
X94645Y-1024383D01*
X96850Y-1024800D01*
X99055Y-1024383D01*
X100945Y-1022717D01*
X102205Y-1019800D01*
G01Y-1024800D02*
Y-1008134D01*
G01X127720Y-1024800D02*
Y-1008134D01*
G01Y-1011050D02*
X126460Y-1009384D01*
X124570Y-1008550D01*
X122365Y-1008134D01*
X120160Y-1008967D01*
X118270Y-1010633D01*
X117010Y-1013134D01*
X116380Y-1016467D01*
X117010Y-1019800D01*
X118270Y-1022301D01*
X120160Y-1023967D01*
X122365Y-1024800D01*
X124570Y-1024383D01*
X126460Y-1023134D01*
X127720Y-1021467D01*
G01X141895Y-1024800D02*
Y-1008134D01*
G01Y-1012300D02*
X143155Y-1010217D01*
X145045Y-1008550D01*
X147565Y-1008134D01*
X149770Y-1008550D01*
X151660Y-1010217D01*
X152605Y-1013134D01*
Y-1024800D01*
G01X172450Y-999800D02*
Y-1024800D01*
G01X168040Y-1008134D02*
X176860D01*
G01X203320Y-1024800D02*
Y-1008134D01*
G01Y-1011050D02*
X202060Y-1009384D01*
X200170Y-1008550D01*
X197965Y-1008134D01*
X195760Y-1008967D01*
X193870Y-1010633D01*
X192610Y-1013134D01*
X191980Y-1016467D01*
X192610Y-1019800D01*
X193870Y-1022301D01*
X195760Y-1023967D01*
X197965Y-1024800D01*
X200170Y-1024383D01*
X202060Y-1023134D01*
X203320Y-1021467D01*
G01X49820Y-1042350D02*
X51387D01*
Y-1044240D01*
X50917Y-1044870D01*
X50368Y-1045290D01*
X49585Y-1045500D01*
X48802Y-1045290D01*
X48253Y-1044870D01*
X47783Y-1044240D01*
X47470Y-1043505D01*
X47313Y-1042665D01*
Y-1041930D01*
X47470Y-1041300D01*
X47783Y-1040565D01*
X48253Y-1039935D01*
X48723Y-1039515D01*
X49350Y-1039200D01*
X49898D01*
X50525Y-1039410D01*
X50995Y-1039830D01*
G01X53927Y-1039200D02*
Y-1043715D01*
X54240Y-1044660D01*
X54867Y-1045290D01*
X55650Y-1045500D01*
X56433Y-1045290D01*
X57060Y-1044660D01*
X57373Y-1043715D01*
Y-1039200D01*
G01X61010D02*
X62890D01*
G01X61950D02*
Y-1045500D01*
G01X61010D02*
X62890D01*
G01X66605Y-1044660D02*
X67232Y-1045185D01*
X67937Y-1045500D01*
X68563D01*
X69190Y-1045185D01*
X69660Y-1044660D01*
X69895Y-1043925D01*
X69738Y-1043190D01*
X69347Y-1042560D01*
X68642Y-1042140D01*
X67702Y-1041930D01*
X67153Y-1041510D01*
X66918Y-1040775D01*
X67075Y-1040040D01*
X67467Y-1039515D01*
X68015Y-1039200D01*
X68563D01*
X69112Y-1039410D01*
X69582Y-1039935D01*
G01X72905Y-1045500D02*
Y-1039200D01*
G01X76195D02*
Y-1045500D01*
G01Y-1042350D02*
X72905D01*
G01X78892Y-1045500D02*
X80850Y-1039200D01*
X82808Y-1045500D01*
G01X82103Y-1043295D02*
X79597D01*
G01X85348Y-1045500D02*
Y-1039200D01*
X88952Y-1045500D01*
Y-1039200D01*
G01X98027Y-1045500D02*
Y-1039200D01*
X99593D01*
X100220Y-1039515D01*
X100690Y-1039935D01*
X101082Y-1040565D01*
X101395Y-1041300D01*
X101473Y-1042350D01*
X101395Y-1043400D01*
X101082Y-1044135D01*
X100690Y-1044765D01*
X100220Y-1045185D01*
X99593Y-1045500D01*
X98027D01*
G01X105110Y-1039200D02*
X106990D01*
G01X106050D02*
Y-1045500D01*
G01X105110D02*
X106990D01*
G01X110705Y-1044660D02*
X111332Y-1045185D01*
X112037Y-1045500D01*
X112663D01*
X113290Y-1045185D01*
X113760Y-1044660D01*
X113995Y-1043925D01*
X113838Y-1043190D01*
X113447Y-1042560D01*
X112742Y-1042140D01*
X111802Y-1041930D01*
X111253Y-1041510D01*
X111018Y-1040775D01*
X111175Y-1040040D01*
X111567Y-1039515D01*
X112115Y-1039200D01*
X112663D01*
X113212Y-1039410D01*
X113682Y-1039935D01*
G01X118650Y-1039200D02*
Y-1045500D01*
G01X116848Y-1039200D02*
X120452D01*
G01X124950Y-1045710D02*
X124793Y-1045605D01*
Y-1045395D01*
X124950Y-1045290D01*
X125107Y-1045395D01*
Y-1045605D01*
X124950Y-1045710D01*
G01X131093Y-1046655D02*
X131407Y-1045290D01*
G01X137550Y-1039200D02*
Y-1045500D01*
G01X135748Y-1039200D02*
X139352D01*
G01X141892Y-1045500D02*
X143850Y-1039200D01*
X145808Y-1045500D01*
G01X145103Y-1043295D02*
X142597D01*
G01X150150Y-1045500D02*
X149523Y-1045395D01*
X148975Y-1044975D01*
X148505Y-1044345D01*
X148192Y-1043610D01*
X148035Y-1042770D01*
Y-1041930D01*
X148192Y-1041090D01*
X148505Y-1040355D01*
X148975Y-1039725D01*
X149523Y-1039305D01*
X150150Y-1039200D01*
X150777Y-1039305D01*
X151325Y-1039725D01*
X151795Y-1040355D01*
X152108Y-1041090D01*
X152265Y-1041930D01*
Y-1042770D01*
X152108Y-1043610D01*
X151795Y-1044345D01*
X151325Y-1044975D01*
X150777Y-1045395D01*
X150150Y-1045500D01*
G01X156450D02*
Y-1042665D01*
X154883Y-1039200D01*
G01X158017D02*
X156450Y-1042665D01*
G01X161027Y-1039200D02*
Y-1043715D01*
X161340Y-1044660D01*
X161967Y-1045290D01*
X162750Y-1045500D01*
X163533Y-1045290D01*
X164160Y-1044660D01*
X164473Y-1043715D01*
Y-1039200D01*
G01X167092Y-1045500D02*
X169050Y-1039200D01*
X171008Y-1045500D01*
G01X170303Y-1043295D02*
X167797D01*
G01X173548Y-1045500D02*
Y-1039200D01*
X177152Y-1045500D01*
Y-1039200D01*
G01X51073Y-1049725D02*
X50603Y-1049410D01*
X50055Y-1049200D01*
X49428D01*
X48723Y-1049515D01*
X48175Y-1050040D01*
X47783Y-1050670D01*
X47470Y-1051720D01*
X47392Y-1052665D01*
X47548Y-1053610D01*
X47783Y-1054240D01*
X48253Y-1054870D01*
X48802Y-1055290D01*
X49350Y-1055500D01*
X49898D01*
X50447Y-1055290D01*
X50917Y-1054975D01*
X51308Y-1054555D01*
G01X54710Y-1049200D02*
X56590D01*
G01X55650D02*
Y-1055500D01*
G01X54710D02*
X56590D01*
G01X61950Y-1049200D02*
Y-1055500D01*
G01X60148Y-1049200D02*
X63752D01*
G01X68250Y-1055500D02*
Y-1052665D01*
X66683Y-1049200D01*
G01X69817D02*
X68250Y-1052665D01*
G01X79127Y-1054240D02*
X79597Y-1054975D01*
X80223Y-1055395D01*
X80928Y-1055500D01*
X81555Y-1055395D01*
X82182Y-1054870D01*
X82573Y-1054240D01*
X82652Y-1053610D01*
X82495Y-1052875D01*
X81947Y-1052350D01*
X81398Y-1052140D01*
X80693D01*
G01X81398D02*
X81868Y-1051825D01*
X82260Y-1051300D01*
X82417Y-1050670D01*
X82260Y-1050040D01*
X81868Y-1049515D01*
X81163Y-1049200D01*
X80458Y-1049305D01*
X79753Y-1049725D01*
G01X85427Y-1054240D02*
X85897Y-1054975D01*
X86523Y-1055395D01*
X87228Y-1055500D01*
X87855Y-1055395D01*
X88482Y-1054870D01*
X88873Y-1054240D01*
X88952Y-1053610D01*
X88795Y-1052875D01*
X88247Y-1052350D01*
X87698Y-1052140D01*
X86993D01*
G01X87698D02*
X88168Y-1051825D01*
X88560Y-1051300D01*
X88717Y-1050670D01*
X88560Y-1050040D01*
X88168Y-1049515D01*
X87463Y-1049200D01*
X86758Y-1049305D01*
X86053Y-1049725D01*
G01X91727Y-1054240D02*
X92197Y-1054975D01*
X92823Y-1055395D01*
X93528Y-1055500D01*
X94155Y-1055395D01*
X94782Y-1054870D01*
X95173Y-1054240D01*
X95252Y-1053610D01*
X95095Y-1052875D01*
X94547Y-1052350D01*
X93998Y-1052140D01*
X93293D01*
G01X93998D02*
X94468Y-1051825D01*
X94860Y-1051300D01*
X95017Y-1050670D01*
X94860Y-1050040D01*
X94468Y-1049515D01*
X93763Y-1049200D01*
X93058Y-1049305D01*
X92353Y-1049725D01*
G01X99593Y-1055500D02*
X99750Y-1054135D01*
X99985Y-1052980D01*
X100298Y-1051930D01*
X100690Y-1050775D01*
X101317Y-1049200D01*
X98183D01*
G01X105893Y-1055500D02*
X106050Y-1054135D01*
X106285Y-1052980D01*
X106598Y-1051930D01*
X106990Y-1050775D01*
X107617Y-1049200D01*
X104483D01*
G01X112193Y-1056655D02*
X112507Y-1055290D01*
G01X118650Y-1049200D02*
Y-1055500D01*
G01X116848Y-1049200D02*
X120452D01*
G01X122992Y-1055500D02*
X124950Y-1049200D01*
X126908Y-1055500D01*
G01X126203Y-1053295D02*
X123697D01*
G01X130310Y-1049200D02*
X132190D01*
G01X131250D02*
Y-1055500D01*
G01X130310D02*
X132190D01*
G01X135200Y-1049200D02*
X136297Y-1055500D01*
X137550Y-1049200D01*
X138803Y-1055500D01*
X139900Y-1049200D01*
G01X141892Y-1055500D02*
X143850Y-1049200D01*
X145808Y-1055500D01*
G01X145103Y-1053295D02*
X142597D01*
G01X148348Y-1055500D02*
Y-1049200D01*
X151952Y-1055500D01*
Y-1049200D01*
G01X162358Y-1057600D02*
X161575Y-1056550D01*
X161183Y-1055500D01*
Y-1051300D01*
X161575Y-1050250D01*
X162358Y-1049200D01*
G01X173783Y-1055500D02*
Y-1049200D01*
X175742D01*
X176368Y-1049515D01*
X176760Y-1049935D01*
X176917Y-1050775D01*
X176760Y-1051615D01*
X176290Y-1052140D01*
X175742Y-1052455D01*
X173783D01*
G01X175742D02*
X176917Y-1055500D01*
G01X181650Y-1055710D02*
X181493Y-1055605D01*
Y-1055395D01*
X181650Y-1055290D01*
X181807Y-1055395D01*
Y-1055605D01*
X181650Y-1055710D01*
G01X187950Y-1055500D02*
X187323Y-1055395D01*
X186775Y-1054975D01*
X186305Y-1054345D01*
X185992Y-1053610D01*
X185835Y-1052770D01*
Y-1051930D01*
X185992Y-1051090D01*
X186305Y-1050355D01*
X186775Y-1049725D01*
X187323Y-1049305D01*
X187950Y-1049200D01*
X188577Y-1049305D01*
X189125Y-1049725D01*
X189595Y-1050355D01*
X189908Y-1051090D01*
X190065Y-1051930D01*
Y-1052770D01*
X189908Y-1053610D01*
X189595Y-1054345D01*
X189125Y-1054975D01*
X188577Y-1055395D01*
X187950Y-1055500D01*
G01X194250Y-1055710D02*
X194093Y-1055605D01*
Y-1055395D01*
X194250Y-1055290D01*
X194407Y-1055395D01*
Y-1055605D01*
X194250Y-1055710D01*
G01X202273Y-1049725D02*
X201803Y-1049410D01*
X201255Y-1049200D01*
X200628D01*
X199923Y-1049515D01*
X199375Y-1050040D01*
X198983Y-1050670D01*
X198670Y-1051720D01*
X198592Y-1052665D01*
X198748Y-1053610D01*
X198983Y-1054240D01*
X199453Y-1054870D01*
X200002Y-1055290D01*
X200550Y-1055500D01*
X201098D01*
X201647Y-1055290D01*
X202117Y-1054975D01*
X202508Y-1054555D01*
G01X206850Y-1055710D02*
X206693Y-1055605D01*
Y-1055395D01*
X206850Y-1055290D01*
X207007Y-1055395D01*
Y-1055605D01*
X206850Y-1055710D01*
G01X213542Y-1057600D02*
X214325Y-1056550D01*
X214717Y-1055500D01*
Y-1051300D01*
X214325Y-1050250D01*
X213542Y-1049200D01*
G01X47548Y-1035500D02*
Y-1029200D01*
X51152Y-1035500D01*
Y-1029200D01*
G01X55650Y-1035500D02*
X55023Y-1035395D01*
X54475Y-1034975D01*
X54005Y-1034345D01*
X53692Y-1033610D01*
X53535Y-1032770D01*
Y-1031930D01*
X53692Y-1031090D01*
X54005Y-1030355D01*
X54475Y-1029725D01*
X55023Y-1029305D01*
X55650Y-1029200D01*
X56277Y-1029305D01*
X56825Y-1029725D01*
X57295Y-1030355D01*
X57608Y-1031090D01*
X57765Y-1031930D01*
Y-1032770D01*
X57608Y-1033610D01*
X57295Y-1034345D01*
X56825Y-1034975D01*
X56277Y-1035395D01*
X55650Y-1035500D01*
G01X61950Y-1035710D02*
X61793Y-1035605D01*
Y-1035395D01*
X61950Y-1035290D01*
X62107Y-1035395D01*
Y-1035605D01*
X61950Y-1035710D01*
G01X66762Y-1030250D02*
X67232Y-1029620D01*
X67780Y-1029305D01*
X68407Y-1029200D01*
X69190Y-1029410D01*
X69738Y-1029935D01*
X69895Y-1030565D01*
X69817Y-1031195D01*
X69503Y-1031720D01*
X67937Y-1032770D01*
X67232Y-1033505D01*
X66762Y-1034555D01*
X66605Y-1035500D01*
X69895D01*
G01X74550D02*
Y-1029200D01*
X73610Y-1030460D01*
G01Y-1035500D02*
X75490D01*
G01X80850D02*
Y-1029200D01*
X79910Y-1030460D01*
G01Y-1035500D02*
X81790D01*
G01X86993Y-1036655D02*
X87307Y-1035290D01*
G01X91100Y-1029200D02*
X92197Y-1035500D01*
X93450Y-1029200D01*
X94703Y-1035500D01*
X95800Y-1029200D01*
G01X101317Y-1035500D02*
X98183D01*
Y-1029200D01*
X101317D01*
G01X100063Y-1032245D02*
X98183D01*
G01X104248Y-1035500D02*
Y-1029200D01*
X107852Y-1035500D01*
Y-1029200D01*
G01X110705Y-1035500D02*
Y-1029200D01*
G01X113995D02*
Y-1035500D01*
G01Y-1032350D02*
X110705D01*
G01X116927Y-1029200D02*
Y-1033715D01*
X117240Y-1034660D01*
X117867Y-1035290D01*
X118650Y-1035500D01*
X119433Y-1035290D01*
X120060Y-1034660D01*
X120373Y-1033715D01*
Y-1029200D01*
G01X122992Y-1035500D02*
X124950Y-1029200D01*
X126908Y-1035500D01*
G01X126203Y-1033295D02*
X123697D01*
G01X136062Y-1030250D02*
X136532Y-1029620D01*
X137080Y-1029305D01*
X137707Y-1029200D01*
X138490Y-1029410D01*
X139038Y-1029935D01*
X139195Y-1030565D01*
X139117Y-1031195D01*
X138803Y-1031720D01*
X137237Y-1032770D01*
X136532Y-1033505D01*
X136062Y-1034555D01*
X135905Y-1035500D01*
X139195D01*
G01X142048D02*
Y-1029200D01*
X145652Y-1035500D01*
Y-1029200D01*
G01X148427Y-1035500D02*
Y-1029200D01*
X149993D01*
X150620Y-1029515D01*
X151090Y-1029935D01*
X151482Y-1030565D01*
X151795Y-1031300D01*
X151873Y-1032350D01*
X151795Y-1033400D01*
X151482Y-1034135D01*
X151090Y-1034765D01*
X150620Y-1035185D01*
X149993Y-1035500D01*
X148427D01*
G01X161183D02*
Y-1029200D01*
X163142D01*
X163768Y-1029515D01*
X164160Y-1029935D01*
X164317Y-1030775D01*
X164160Y-1031615D01*
X163690Y-1032140D01*
X163142Y-1032455D01*
X161183D01*
G01X163142D02*
X164317Y-1035500D01*
G01X167327D02*
Y-1029200D01*
X168893D01*
X169520Y-1029515D01*
X169990Y-1029935D01*
X170382Y-1030565D01*
X170695Y-1031300D01*
X170773Y-1032350D01*
X170695Y-1033400D01*
X170382Y-1034135D01*
X169990Y-1034765D01*
X169520Y-1035185D01*
X168893Y-1035500D01*
X167327D01*
G01X175350Y-1035710D02*
X175193Y-1035605D01*
Y-1035395D01*
X175350Y-1035290D01*
X175507Y-1035395D01*
Y-1035605D01*
X175350Y-1035710D01*
G01X243000Y-1004500D02*
Y-1012500D01*
X247000D01*
G01X254800D02*
Y-1007167D01*
G01Y-1008100D02*
X254400Y-1007567D01*
X253800Y-1007300D01*
X253100Y-1007167D01*
X252400Y-1007433D01*
X251800Y-1007967D01*
X251400Y-1008767D01*
X251200Y-1009833D01*
X251400Y-1010900D01*
X251800Y-1011700D01*
X252400Y-1012233D01*
X253100Y-1012500D01*
X253800Y-1012367D01*
X254400Y-1011967D01*
X254800Y-1011434D01*
G01X258900Y-1014900D02*
X259500Y-1015167D01*
X260300Y-1014900D01*
X260800Y-1014367D01*
X261200Y-1013700D01*
X261800Y-1011567D01*
X263100Y-1007167D01*
G01X259900D02*
X261800Y-1011567D01*
G01X267500Y-1008900D02*
X270700D01*
X270400Y-1007967D01*
X269900Y-1007433D01*
X269200Y-1007167D01*
X268500Y-1007300D01*
X267900Y-1007700D01*
X267500Y-1008633D01*
X267300Y-1009434D01*
Y-1010233D01*
X267500Y-1011033D01*
X268000Y-1011833D01*
X268600Y-1012367D01*
X269300Y-1012500D01*
X270000Y-1012233D01*
X270700Y-1011434D01*
G01X275600Y-1012500D02*
Y-1007167D01*
G01Y-1008233D02*
X276100Y-1007700D01*
X276600Y-1007300D01*
X277300Y-1007167D01*
X277800Y-1007300D01*
X278400Y-1007700D01*
G01X262100Y-1054500D02*
X265900D01*
X262100Y-1062500D01*
X265900D01*
G01X272000Y-1057167D02*
Y-1062500D01*
G01Y-1055033D02*
X271800Y-1054900D01*
Y-1054633D01*
X272000Y-1054500D01*
X272200Y-1054633D01*
Y-1054900D01*
X272000Y-1055033D01*
G01X278700Y-1059833D02*
X281300D01*
G01X286200Y-1065167D02*
Y-1057167D01*
G01Y-1058367D02*
X286700Y-1057700D01*
X287200Y-1057300D01*
X288000Y-1057167D01*
X288700Y-1057300D01*
X289400Y-1057967D01*
X289700Y-1058900D01*
X289800Y-1059833D01*
X289700Y-1060767D01*
X289400Y-1061700D01*
X288800Y-1062233D01*
X288000Y-1062500D01*
X287300Y-1062367D01*
X286600Y-1061967D01*
X286200Y-1061434D01*
G01X296000Y-1057167D02*
Y-1062500D01*
G01Y-1055033D02*
X295800Y-1054900D01*
Y-1054633D01*
X296000Y-1054500D01*
X296200Y-1054633D01*
Y-1054900D01*
X296000Y-1055033D01*
G01X302300Y-1062500D02*
Y-1057167D01*
G01Y-1058500D02*
X302700Y-1057833D01*
X303300Y-1057300D01*
X304100Y-1057167D01*
X304800Y-1057300D01*
X305400Y-1057833D01*
X305700Y-1058767D01*
Y-1062500D01*
G01X310600Y-1064500D02*
X311300Y-1065033D01*
X312100Y-1065167D01*
X312800Y-1065033D01*
X313400Y-1064367D01*
X313800Y-1063433D01*
Y-1057167D01*
G01Y-1058233D02*
X313400Y-1057700D01*
X312800Y-1057300D01*
X312100Y-1057167D01*
X311300Y-1057433D01*
X310800Y-1057967D01*
X310400Y-1058900D01*
X310200Y-1059833D01*
X310300Y-1060633D01*
X310700Y-1061567D01*
X311300Y-1062233D01*
X312100Y-1062500D01*
X312700Y-1062367D01*
X313400Y-1061833D01*
X313800Y-1061300D01*
G01X274000Y-1029500D02*
X276500Y-1037500D01*
X279000Y-1029500D01*
G01X286700Y-1030167D02*
X286100Y-1029767D01*
X285400Y-1029500D01*
X284600D01*
X283700Y-1029900D01*
X283000Y-1030567D01*
X282500Y-1031367D01*
X282100Y-1032700D01*
X282000Y-1033900D01*
X282200Y-1035100D01*
X282500Y-1035900D01*
X283100Y-1036700D01*
X283800Y-1037233D01*
X284500Y-1037500D01*
X285200D01*
X285900Y-1037233D01*
X286500Y-1036833D01*
X287000Y-1036300D01*
G01X294700Y-1030167D02*
X294100Y-1029767D01*
X293400Y-1029500D01*
X292600D01*
X291700Y-1029900D01*
X291000Y-1030567D01*
X290500Y-1031367D01*
X290100Y-1032700D01*
X290000Y-1033900D01*
X290200Y-1035100D01*
X290500Y-1035900D01*
X291100Y-1036700D01*
X291800Y-1037233D01*
X292500Y-1037500D01*
X293200D01*
X293900Y-1037233D01*
X294500Y-1036833D01*
X295000Y-1036300D01*
G01X300500Y-1037500D02*
Y-1029500D01*
X299300Y-1031100D01*
G01Y-1037500D02*
X301700D01*
G01X294600Y-1009167D02*
X295300Y-1008233D01*
X295900Y-1007700D01*
X296700Y-1007433D01*
X297400Y-1007700D01*
X297900Y-1008233D01*
X298300Y-1009033D01*
X298400Y-1009967D01*
X298300Y-1010767D01*
X297900Y-1011567D01*
X297300Y-1012233D01*
X296600Y-1012500D01*
X295800Y-1012233D01*
X295100Y-1011434D01*
X294700Y-1010233D01*
X294600Y-1008900D01*
X294800Y-1007167D01*
X295100Y-1006233D01*
X295600Y-1005300D01*
X296300Y-1004633D01*
X297000Y-1004500D01*
X297700Y-1004767D01*
X298200Y-1005433D01*
G01X369600Y-1055833D02*
X370200Y-1055033D01*
X370900Y-1054633D01*
X371700Y-1054500D01*
X372700Y-1054767D01*
X373400Y-1055433D01*
X373600Y-1056233D01*
X373500Y-1057034D01*
X373100Y-1057700D01*
X371100Y-1059033D01*
X370200Y-1059967D01*
X369600Y-1061300D01*
X369400Y-1062500D01*
X373600D01*
G01X379500Y-1054500D02*
X378700Y-1054767D01*
X378100Y-1055433D01*
X377700Y-1056233D01*
X377400Y-1057300D01*
X377300Y-1058500D01*
X377400Y-1059700D01*
X377700Y-1060767D01*
X378100Y-1061567D01*
X378700Y-1062233D01*
X379500Y-1062500D01*
X380300Y-1062233D01*
X380900Y-1061567D01*
X381300Y-1060767D01*
X381600Y-1059700D01*
X381700Y-1058500D01*
X381600Y-1057300D01*
X381300Y-1056233D01*
X380900Y-1055433D01*
X380300Y-1054767D01*
X379500Y-1054500D01*
G01X385600Y-1055833D02*
X386200Y-1055033D01*
X386900Y-1054633D01*
X387700Y-1054500D01*
X388700Y-1054767D01*
X389400Y-1055433D01*
X389600Y-1056233D01*
X389500Y-1057034D01*
X389100Y-1057700D01*
X387100Y-1059033D01*
X386200Y-1059967D01*
X385600Y-1061300D01*
X385400Y-1062500D01*
X389600D01*
G01X393600Y-1055833D02*
X394200Y-1055033D01*
X394900Y-1054633D01*
X395700Y-1054500D01*
X396700Y-1054767D01*
X397400Y-1055433D01*
X397600Y-1056233D01*
X397500Y-1057034D01*
X397100Y-1057700D01*
X395100Y-1059033D01*
X394200Y-1059967D01*
X393600Y-1061300D01*
X393400Y-1062500D01*
X397600D01*
G01X401700Y-1062767D02*
X405300Y-1054500D01*
G01X411500Y-1062500D02*
Y-1054500D01*
X410300Y-1056100D01*
G01Y-1062500D02*
X412700D01*
G01X417600Y-1055833D02*
X418200Y-1055033D01*
X418900Y-1054633D01*
X419700Y-1054500D01*
X420700Y-1054767D01*
X421400Y-1055433D01*
X421600Y-1056233D01*
X421500Y-1057034D01*
X421100Y-1057700D01*
X419100Y-1059033D01*
X418200Y-1059967D01*
X417600Y-1061300D01*
X417400Y-1062500D01*
X421600D01*
G01X425700Y-1062767D02*
X429300Y-1054500D01*
G01X435500Y-1062500D02*
Y-1054500D01*
X434300Y-1056100D01*
G01Y-1062500D02*
X436700D01*
G01X441300Y-1060900D02*
X441900Y-1061833D01*
X442700Y-1062367D01*
X443600Y-1062500D01*
X444400Y-1062367D01*
X445200Y-1061700D01*
X445700Y-1060900D01*
X445800Y-1060100D01*
X445600Y-1059167D01*
X444900Y-1058500D01*
X444200Y-1058233D01*
X443300D01*
G01X444200D02*
X444800Y-1057833D01*
X445300Y-1057167D01*
X445500Y-1056367D01*
X445300Y-1055567D01*
X444800Y-1054900D01*
X443900Y-1054500D01*
X443000Y-1054633D01*
X442100Y-1055167D01*
G01X369300Y-1040000D02*
Y-1032000D01*
X371300D01*
X372100Y-1032400D01*
X372700Y-1032933D01*
X373200Y-1033733D01*
X373600Y-1034667D01*
X373700Y-1036000D01*
X373600Y-1037333D01*
X373200Y-1038267D01*
X372700Y-1039067D01*
X372100Y-1039600D01*
X371300Y-1040000D01*
X369300D01*
G01X377000D02*
X379500Y-1032000D01*
X382000Y-1040000D01*
G01X381100Y-1037200D02*
X377900D01*
G01X385600Y-1040000D02*
Y-1032000D01*
X389400D01*
G01X388000Y-1035867D02*
X385600D01*
G01X395500Y-1032000D02*
X394700Y-1032267D01*
X394100Y-1032933D01*
X393700Y-1033733D01*
X393400Y-1034800D01*
X393300Y-1036000D01*
X393400Y-1037200D01*
X393700Y-1038267D01*
X394100Y-1039067D01*
X394700Y-1039733D01*
X395500Y-1040000D01*
X396300Y-1039733D01*
X396900Y-1039067D01*
X397300Y-1038267D01*
X397600Y-1037200D01*
X397700Y-1036000D01*
X397600Y-1034800D01*
X397300Y-1033733D01*
X396900Y-1032933D01*
X396300Y-1032267D01*
X395500Y-1032000D01*
G01X403500D02*
Y-1040000D01*
G01X401200Y-1032000D02*
X405800D01*
G01X409500Y-1040000D02*
Y-1032000D01*
X411900D01*
X412700Y-1032400D01*
X413300Y-1033333D01*
X413500Y-1034400D01*
X413300Y-1035467D01*
X412800Y-1036267D01*
X411900Y-1036667D01*
X409500D01*
G01X420300Y-1035733D02*
X420700Y-1035333D01*
X421000Y-1034667D01*
X421200Y-1033733D01*
X421000Y-1032933D01*
X420600Y-1032400D01*
X419900Y-1032000D01*
X417200D01*
Y-1040000D01*
X420500D01*
X421200Y-1039467D01*
X421600Y-1038667D01*
X421800Y-1037733D01*
X421600Y-1036800D01*
X421000Y-1036000D01*
X420300Y-1035733D01*
X417200D01*
G01X427500Y-1040000D02*
Y-1032000D01*
X426300Y-1033600D01*
G01Y-1040000D02*
X428700D01*
G01X433000D02*
X435500Y-1032000D01*
X438000Y-1040000D01*
G01X437100Y-1037200D02*
X433900D01*
G01X441600Y-1040000D02*
Y-1032000D01*
X445400D01*
G01X444000Y-1035867D02*
X441600D01*
G01X451500Y-1032000D02*
X450700Y-1032267D01*
X450100Y-1032933D01*
X449700Y-1033733D01*
X449400Y-1034800D01*
X449300Y-1036000D01*
X449400Y-1037200D01*
X449700Y-1038267D01*
X450100Y-1039067D01*
X450700Y-1039733D01*
X451500Y-1040000D01*
X452300Y-1039733D01*
X452900Y-1039067D01*
X453300Y-1038267D01*
X453600Y-1037200D01*
X453700Y-1036000D01*
X453600Y-1034800D01*
X453300Y-1033733D01*
X452900Y-1032933D01*
X452300Y-1032267D01*
X451500Y-1032000D01*
G01X389600Y-1012500D02*
Y-1004500D01*
X393400D01*
G01X392000Y-1008367D02*
X389600D01*
G01X399500Y-1004500D02*
X398700Y-1004767D01*
X398100Y-1005433D01*
X397700Y-1006233D01*
X397400Y-1007300D01*
X397300Y-1008500D01*
X397400Y-1009700D01*
X397700Y-1010767D01*
X398100Y-1011567D01*
X398700Y-1012233D01*
X399500Y-1012500D01*
X400300Y-1012233D01*
X400900Y-1011567D01*
X401300Y-1010767D01*
X401600Y-1009700D01*
X401700Y-1008500D01*
X401600Y-1007300D01*
X401300Y-1006233D01*
X400900Y-1005433D01*
X400300Y-1004767D01*
X399500Y-1004500D01*
G01X407500D02*
Y-1012500D01*
G01X405200Y-1004500D02*
X409800D01*
G01X412500Y-1015167D02*
X418500D01*
G01X421500Y-1012500D02*
Y-1004500D01*
X423900D01*
X424700Y-1004900D01*
X425300Y-1005833D01*
X425500Y-1006900D01*
X425300Y-1007967D01*
X424800Y-1008767D01*
X423900Y-1009167D01*
X421500D01*
G01X429300Y-1012500D02*
Y-1004500D01*
X431300D01*
X432100Y-1004900D01*
X432700Y-1005433D01*
X433200Y-1006233D01*
X433600Y-1007167D01*
X433700Y-1008500D01*
X433600Y-1009833D01*
X433200Y-1010767D01*
X432700Y-1011567D01*
X432100Y-1012100D01*
X431300Y-1012500D01*
X429300D01*
G01X440300Y-1008233D02*
X440700Y-1007833D01*
X441000Y-1007167D01*
X441200Y-1006233D01*
X441000Y-1005433D01*
X440600Y-1004900D01*
X439900Y-1004500D01*
X437200D01*
Y-1012500D01*
X440500D01*
X441200Y-1011967D01*
X441600Y-1011167D01*
X441800Y-1010233D01*
X441600Y-1009300D01*
X441000Y-1008500D01*
X440300Y-1008233D01*
X437200D01*
G01X444500Y-1015167D02*
X450500D01*
G01X456300Y-1008233D02*
X456700Y-1007833D01*
X457000Y-1007167D01*
X457200Y-1006233D01*
X457000Y-1005433D01*
X456600Y-1004900D01*
X455900Y-1004500D01*
X453200D01*
Y-1012500D01*
X456500D01*
X457200Y-1011967D01*
X457600Y-1011167D01*
X457800Y-1010233D01*
X457600Y-1009300D01*
X457000Y-1008500D01*
X456300Y-1008233D01*
X453200D01*
G01X461300Y-1012500D02*
Y-1004500D01*
X463300D01*
X464100Y-1004900D01*
X464700Y-1005433D01*
X465200Y-1006233D01*
X465600Y-1007167D01*
X465700Y-1008500D01*
X465600Y-1009833D01*
X465200Y-1010767D01*
X464700Y-1011567D01*
X464100Y-1012100D01*
X463300Y-1012500D01*
X461300D01*
G01X468500Y-1015167D02*
X474500D01*
G01X480100Y-1008500D02*
X482100D01*
Y-1010900D01*
X481500Y-1011700D01*
X480800Y-1012233D01*
X479800Y-1012500D01*
X478800Y-1012233D01*
X478100Y-1011700D01*
X477500Y-1010900D01*
X477100Y-1009967D01*
X476900Y-1008900D01*
Y-1007967D01*
X477100Y-1007167D01*
X477500Y-1006233D01*
X478100Y-1005433D01*
X478700Y-1004900D01*
X479500Y-1004500D01*
X480200D01*
X481000Y-1004767D01*
X481600Y-1005300D01*
G01X485500Y-1012500D02*
Y-1004500D01*
X487900D01*
X488700Y-1004900D01*
X489300Y-1005833D01*
X489500Y-1006900D01*
X489300Y-1007967D01*
X488800Y-1008767D01*
X487900Y-1009167D01*
X485500D01*
G01X493300Y-1004500D02*
Y-1010233D01*
X493700Y-1011434D01*
X494500Y-1012233D01*
X495500Y-1012500D01*
X496500Y-1012233D01*
X497300Y-1011434D01*
X497700Y-1010233D01*
Y-1004500D01*
G01X458000Y-1065500D02*
Y-1057500D01*
X456800Y-1059100D01*
G01Y-1065500D02*
X459200D01*
G01X464100Y-1062167D02*
X464800Y-1061233D01*
X465400Y-1060700D01*
X466200Y-1060433D01*
X466900Y-1060700D01*
X467400Y-1061233D01*
X467800Y-1062033D01*
X467900Y-1062967D01*
X467800Y-1063767D01*
X467400Y-1064567D01*
X466800Y-1065233D01*
X466100Y-1065500D01*
X465300Y-1065233D01*
X464600Y-1064434D01*
X464200Y-1063233D01*
X464100Y-1061900D01*
X464300Y-1060167D01*
X464600Y-1059233D01*
X465100Y-1058300D01*
X465800Y-1057633D01*
X466500Y-1057500D01*
X467200Y-1057767D01*
X467700Y-1058433D01*
G01X474000Y-1065767D02*
X473800Y-1065633D01*
Y-1065367D01*
X474000Y-1065233D01*
X474200Y-1065367D01*
Y-1065633D01*
X474000Y-1065767D01*
G01X480100Y-1062167D02*
X480800Y-1061233D01*
X481400Y-1060700D01*
X482200Y-1060433D01*
X482900Y-1060700D01*
X483400Y-1061233D01*
X483800Y-1062033D01*
X483900Y-1062967D01*
X483800Y-1063767D01*
X483400Y-1064567D01*
X482800Y-1065233D01*
X482100Y-1065500D01*
X481300Y-1065233D01*
X480600Y-1064434D01*
X480200Y-1063233D01*
X480100Y-1061900D01*
X480300Y-1060167D01*
X480600Y-1059233D01*
X481100Y-1058300D01*
X481800Y-1057633D01*
X482500Y-1057500D01*
X483200Y-1057767D01*
X483700Y-1058433D01*
G01X503000Y-1065500D02*
Y-1057500D01*
X501800Y-1059100D01*
G01Y-1065500D02*
X504200D01*
G01X510800D02*
X511000Y-1063767D01*
X511300Y-1062300D01*
X511700Y-1060967D01*
X512200Y-1059500D01*
X513000Y-1057500D01*
X509000D01*
G01X519000Y-1065767D02*
X518800Y-1065633D01*
Y-1065367D01*
X519000Y-1065233D01*
X519200Y-1065367D01*
Y-1065633D01*
X519000Y-1065767D01*
G01X525100Y-1058833D02*
X525700Y-1058033D01*
X526400Y-1057633D01*
X527200Y-1057500D01*
X528200Y-1057767D01*
X528900Y-1058433D01*
X529100Y-1059233D01*
X529000Y-1060034D01*
X528600Y-1060700D01*
X526600Y-1062033D01*
X525700Y-1062967D01*
X525100Y-1064300D01*
X524900Y-1065500D01*
X529100D01*
G01X523100Y-1040500D02*
Y-1032500D01*
X526900D01*
G01X525500Y-1036367D02*
X523100D01*
M02*
